FILE_TYPE = MACRO_DRAWING;
SET COLOR_WIRE YELLOW;
SET COLOR_PROP MONO;
SET COLOR_DOT WHITE;
SET COLOR_ARC YELLOW;
SET COLOR_BODY GREEN;
SET COLOR_NOTE MONO;
SET PROP_DISPLAY VALUE;
SET PAGE_NUMBER P196;
FORCEADD CAP_A..1
(-2200 4500);
FORCEPROP 1 LASTPIN (-2200 4400) $PN 2
J 0
(-2190 4380);
DISPLAY 0.617021 (-2190 4380);
PAINT ORANGE (-2190 4380);
FORCEPROP 1 LASTPIN (-2200 4600) $PN 1
J 0
(-2190 4580);
DISPLAY 0.617021 (-2190 4580);
PAINT ORANGE (-2190 4580);
FORCEPROP 1 LAST TOLERANCE 10%
J 0
(-2150 4450);
DISPLAY 0.617021 (-2150 4450);
PAINT SKYBLUE (-2150 4450);
FORCEPROP 2 LAST NO_XNET_CONNECTION 1
J 0
(-2150 4700);
PAINT MONO (-2150 4700);
FORCEPROP 1 LAST VOLTAGE 6.3V
J 0
(-2150 4500);
DISPLAY 0.617021 (-2150 4500);
PAINT SKYBLUE (-2150 4500);
FORCEPROP 1 LAST PACK_TYPE 0402V
J 0
(-2150 4300);
DISPLAY 0.617021 (-2150 4300);
PAINT SKYBLUE (-2150 4300);
FORCEPROP 1 LAST VALUE 1.0UF
J 0
(-2150 4550);
DISPLAY 0.617021 (-2150 4550);
PAINT SKYBLUE (-2150 4550);
FORCEPROP 1 LAST LOCATION C2U26
J 0
(-2150 4600);
DISPLAY 0.617021 (-2150 4600);
PAINT AQUA (-2150 4600);
FORCEPROP 1 LAST MATERIAL X6S
J 0
(-2150 4400);
DISPLAY 0.617021 (-2150 4400);
PAINT SKYBLUE (-2150 4400);
FORCEPROP 1 LAST PART_NUMBER D97712-004
J 0
(-2150 4350);
DISPLAY 0.617021 (-2150 4350);
PAINT BLUE (-2150 4350);
FORCEPROP 2 LAST CDS_LIB dev_discrete
J 0
(-2200 4500);
PAINT ORANGE (-2200 4500);
DISPLAY INVISIBLE (-2200 4500);
FORCEPROP 2 LAST CDS_LOCATION C2U26
J 0
(-2150 4600);
DISPLAY 0.617021 (-2150 4600);
PAINT AQUA (-2150 4600);
DISPLAY INVISIBLE (-2150 4600);
FORCEPROP 1 LAST PATH I102
J 0
(-2150 4650);
DISPLAY 0.978723 (-2150 4650);
PAINT WHITE (-2150 4650);
DISPLAY INVISIBLE (-2150 4650);
FORCEPROP 2 LAST SEC 1
J 0
(-2150 4700);
DISPLAY 0.680851 (-2150 4700);
PAINT MONO (-2150 4700);
DISPLAY INVISIBLE (-2150 4700);
FORCEPROP 2 LAST BOM_COST SB
J 0
(-2150 4650);
DISPLAY 1.659574 (-2150 4650);
PAINT WHITE (-2150 4650);
DISPLAY INVISIBLE (-2150 4650);
FORCEPROP 2 LAST CDS_SEC 1
J 0
(-2150 4750);
PAINT ORANGE (-2150 4750);
DISPLAY INVISIBLE (-2150 4750);
FORCEPROP 2 LAST ROOM SB_VRD
J 0
(-2150 4650);
DISPLAY 1.659574 (-2150 4650);
PAINT WHITE (-2150 4650);
DISPLAY INVISIBLE (-2150 4650);
FORCEPROP 2 LAST SEC_TYPE 0402V
J 0
(-2150 4700);
DISPLAY 1.021277 (-2150 4700);
PAINT ORANGE (-2150 4700);
DISPLAY INVISIBLE (-2150 4700);
FORCEADD DIODE..3
(825 3650);
FORCEPROP 1 LAST PACK_TYPE SMLF
J 0
(800 3410);
DISPLAY 0.617021 (800 3410);
PAINT SKYBLUE (800 3410);
FORCEPROP 1 LAST VALUE BAT54WS
J 0
(800 3525);
DISPLAY 0.617021 (800 3525);
PAINT SKYBLUE (800 3525);
FORCEPROP 1 LAST MATERIAL IC
J 0
(800 3472);
DISPLAY 0.617021 (800 3472);
PAINT SKYBLUE (800 3472);
FORCEPROP 1 LASTPIN (725 3650) $PN 1
J 2
(760 3660);
DISPLAY 0.617021 (760 3660);
PAINT AQUA (760 3660);
FORCEPROP 1 LAST LOCATION CR7E1
J 0
(798 3806);
DISPLAY 0.617021 (798 3806);
PAINT AQUA (798 3806);
FORCEPROP 1 LASTPIN (925 3650) $PN 2
J 0
(900 3660);
DISPLAY 0.617021 (900 3660);
PAINT AQUA (900 3660);
FORCEPROP 1 LAST PART_NUMBER C73510-001
J 0
(800 3750);
DISPLAY 0.617021 (800 3750);
PAINT BLUE (800 3750);
FORCEPROP 1 LAST PATH I103
J 0
(805 3860);
DISPLAY 0.978723 (805 3860);
PAINT PINK (805 3860);
DISPLAY INVISIBLE (805 3860);
FORCEPROP 2 LAST CDS_LOCATION CR7E1
J 0
(798 3806);
DISPLAY 0.617021 (798 3806);
PAINT AQUA (798 3806);
DISPLAY INVISIBLE (798 3806);
FORCEPROP 2 LAST SEC 1
J 0
(825 3925);
PAINT MONO (825 3925);
DISPLAY INVISIBLE (825 3925);
FORCEPROP 2 LAST SEC_TYPE SMLF
J 0
(825 3925);
DISPLAY 1.021277 (825 3925);
PAINT ORANGE (825 3925);
DISPLAY INVISIBLE (825 3925);
FORCEPROP 2 LAST CDS_LIB mstr_discrete
J 0
(825 3650);
PAINT ORANGE (825 3650);
DISPLAY INVISIBLE (825 3650);
FORCEADD TPS3700..1
(-500 2300);
FORCEPROP 2 LASTPIN (-800 2150) $PN 3
J 2
(-810 2160);
DISPLAY 0.617021 (-810 2160);
PAINT MONO (-810 2160);
FORCEPROP 2 LASTPIN (-800 2400) $PN 2
J 2
(-810 2410);
DISPLAY 0.617021 (-810 2410);
PAINT MONO (-810 2410);
FORCEPROP 1 LAST MATERIAL IC
J 0
(-750 2550);
DISPLAY 0.617021 (-750 2550);
PAINT SKYBLUE (-750 2550);
FORCEPROP 2 LASTPIN (-200 2150) $PN 5
J 0
(-190 2160);
DISPLAY 0.617021 (-190 2160);
PAINT MONO (-190 2160);
FORCEPROP 2 LASTPIN (-200 2300) $PN 1
J 0
(-190 2310);
DISPLAY 0.617021 (-190 2310);
PAINT MONO (-190 2310);
FORCEPROP 2 LASTPIN (-200 2400) $PN 6
J 0
(-190 2410);
DISPLAY 0.617021 (-190 2410);
PAINT MONO (-190 2410);
FORCEPROP 1 LAST LOCATION U8D8
J 0
(-750 2600);
DISPLAY 0.617021 (-750 2600);
PAINT AQUA (-750 2600);
FORCEPROP 1 LAST PART_NUMBER H69492-001
J 0
(-750 2050);
DISPLAY 0.617021 (-750 2050);
PAINT BLUE (-750 2050);
FORCEPROP 2 LASTPIN (-800 2250) $PN 4
J 2
(-810 2260);
DISPLAY 0.617021 (-810 2260);
PAINT MONO (-810 2260);
FORCEPROP 2 LAST ROOM V_SUPER
J 0
(-750 2650);
DISPLAY 1.021277 (-750 2650);
PAINT ORANGE (-750 2650);
DISPLAY INVISIBLE (-750 2650);
FORCEPROP 2 LAST $SEC 1
J 0
(-750 2650);
PAINT MONO (-750 2650);
DISPLAY INVISIBLE (-750 2650);
FORCEPROP 2 LAST CDS_SEC 1
J 0
(-750 2650);
PAINT MONO (-750 2650);
DISPLAY INVISIBLE (-750 2650);
FORCEPROP 1 LAST PACK_TYPE SM
J 0
(-750 2650);
PAINT SKYBLUE (-750 2650);
DISPLAY INVISIBLE (-750 2650);
FORCEPROP 2 LAST CDS_LIB mstr_vreg
J 0
(-500 2300);
PAINT ORANGE (-500 2300);
DISPLAY INVISIBLE (-500 2300);
FORCEPROP 1 LAST CDS_LMAN_SYM_OUTLINE -250,200,250,-200
J 0
(-500 2300);
DISPLAY 0.468085 (-500 2300);
PAINT GREEN (-500 2300);
DISPLAY INVISIBLE (-500 2300);
FORCEPROP 1 LAST PATH I104
J 0
(-500 2550);
PAINT GREEN (-500 2550);
DISPLAY INVISIBLE (-500 2550);
FORCEADD CAP_A..1
(-1000 1950);
FORCEPROP 1 LAST MATERIAL X7R
J 0
(-950 1850);
DISPLAY 0.617021 (-950 1850);
PAINT SKYBLUE (-950 1850);
FORCEPROP 1 LAST VOLTAGE 16V
J 0
(-950 1950);
DISPLAY 0.617021 (-950 1950);
PAINT SKYBLUE (-950 1950);
FORCEPROP 1 LAST LOCATION C8D4
J 0
(-950 2050);
DISPLAY 0.617021 (-950 2050);
PAINT AQUA (-950 2050);
FORCEPROP 1 LAST TOLERANCE 10%
J 0
(-950 1900);
DISPLAY 0.617021 (-950 1900);
PAINT SKYBLUE (-950 1900);
FORCEPROP 1 LAST VALUE 0.1UF
J 0
(-950 2000);
DISPLAY 0.617021 (-950 2000);
PAINT SKYBLUE (-950 2000);
FORCEPROP 1 LAST PART_NUMBER A36096-030
J 0
(-950 1800);
DISPLAY 0.617021 (-950 1800);
PAINT BLUE (-950 1800);
FORCEPROP 1 LAST PACK_TYPE 0402V
J 0
(-950 1750);
DISPLAY 0.617021 (-950 1750);
PAINT SKYBLUE (-950 1750);
FORCEPROP 2 LAST CDS_LIB dev_discrete
J 0
(-1000 1950);
PAINT ORANGE (-1000 1950);
DISPLAY INVISIBLE (-1000 1950);
FORCEPROP 1 LASTPIN (-1000 1850) $PN 2
J 0
(-990 1830);
DISPLAY 0.787234 (-990 1830);
PAINT ORANGE (-990 1830);
DISPLAY INVISIBLE (-990 1830);
FORCEPROP 1 LASTPIN (-1000 2050) $PN 1
J 0
(-990 2030);
DISPLAY 0.787234 (-990 2030);
PAINT ORANGE (-990 2030);
DISPLAY INVISIBLE (-990 2030);
FORCEPROP 2 LAST ROOM V_SUPER
J 0
(-950 2100);
DISPLAY 1.021277 (-950 2100);
PAINT ORANGE (-950 2100);
DISPLAY INVISIBLE (-950 2100);
FORCEPROP 1 LAST PATH I105
J 0
(-950 2100);
DISPLAY 0.978723 (-950 2100);
PAINT WHITE (-950 2100);
DISPLAY INVISIBLE (-950 2100);
FORCEADD RES..1
(1350 2400);
FORCEPROP 1 LASTPIN (1250 2400) $PN 1
J 0
(1262 2412);
DISPLAY 0.617021 (1262 2412);
PAINT ORANGE (1262 2412);
FORCEPROP 1 LAST WATTAGE 1/16W
J 2
(1325 2250);
DISPLAY 0.617021 (1325 2250);
PAINT SKYBLUE (1325 2250);
FORCEPROP 1 LAST VALUE 100.0
J 2
(1325 2300);
DISPLAY 0.617021 (1325 2300);
PAINT SKYBLUE (1325 2300);
FORCEPROP 1 LAST MATERIAL CHIP
J 0
(1350 2250);
DISPLAY 0.617021 (1350 2250);
PAINT SKYBLUE (1350 2250);
FORCEPROP 1 LAST TOLERANCE 1%
J 0
(1350 2300);
DISPLAY 0.617021 (1350 2300);
PAINT SKYBLUE (1350 2300);
FORCEPROP 1 LASTPIN (1450 2400) $PN 2
J 0
(1412 2412);
DISPLAY 0.617021 (1412 2412);
PAINT ORANGE (1412 2412);
FORCEPROP 1 LAST LOCATION R8D42
J 0
(1300 2450);
DISPLAY 0.617021 (1300 2450);
PAINT AQUA (1300 2450);
FORCEPROP 1 LAST PART_NUMBER G21796-017
J 0
(1300 2500);
DISPLAY 0.617021 (1300 2500);
PAINT BLUE (1300 2500);
FORCEPROP 1 LAST PACK_TYPE 0402
J 0
(1600 2250);
DISPLAY 0.617021 (1600 2250);
PAINT SKYBLUE (1600 2250);
FORCEPROP 2 LAST CDS_LIB mstr_discrete
J 0
(1350 2400);
PAINT ORANGE (1350 2400);
DISPLAY INVISIBLE (1350 2400);
FORCEPROP 1 LAST PATH I106
J 0
(1300 2550);
DISPLAY 0.978723 (1300 2550);
PAINT WHITE (1300 2550);
DISPLAY INVISIBLE (1300 2550);
FORCEPROP 0 LAST ROOM V_SUPER
J 0
(1300 2600);
DISPLAY 1.021277 (1300 2600);
PAINT ORANGE (1300 2600);
DISPLAY INVISIBLE (1300 2600);
FORCEPROP 2 LAST SEC_TYPE 0402
J 0
(1300 2600);
DISPLAY 1.021277 (1300 2600);
PAINT ORANGE (1300 2600);
DISPLAY INVISIBLE (1300 2600);
FORCEPROP 2 LAST SEC 1
J 0
(1300 2600);
PAINT MONO (1300 2600);
DISPLAY INVISIBLE (1300 2600);
FORCEADD OFFPAGE..2
(1850 2400);
FORCEPROP 2 LASTPIN (1800 2400) SIG_NAME PWRGD_P12V_MAIN
J 2
(1790 2410);
DISPLAY 0.617021 (1790 2410);
PAINT ORANGE (1790 2410);
FORCEPROP 2 LAST $XR0 191 
J 0
(2039 2400);
DISPLAY 0.638298 (2039 2400);
PAINT MONO (2039 2400);
FORCEPROP 2 LAST CDS_LIB mstr_standard
J 0
(1850 2400);
PAINT ORANGE (1850 2400);
DISPLAY INVISIBLE (1850 2400);
FORCEPROP 2 LAST PATH I107
J 0
(2025 2475);
DISPLAY 1.021277 (2025 2475);
PAINT ORANGE (2025 2475);
DISPLAY INVISIBLE (2025 2475);
FORCEPROP 1 LAST OFFPAGE TRUE
J 0
(2175 2275);
DISPLAY 0.872340 (2175 2275);
PAINT GREEN (2175 2275);
DISPLAY INVISIBLE (2175 2275);
FORCEPROP 1 LAST COMMENT_BODY TRUE
J 0
(1805 2305);
DISPLAY 0.872340 (1805 2305);
PAINT GREEN (1805 2305);
DISPLAY INVISIBLE (1805 2305);
FORCEADD GND..1
(-150 2000);
FORCEPROP 3 LASTPIN (-150 2050) SIG_NAME GND\g
J 0
(-140 2060);
DISPLAY 0.659574 (-140 2060);
PAINT MONO (-140 2060);
DISPLAY INVISIBLE (-140 2060);
FORCEPROP 1 LAST PATH I108
J 0
(-75 2000);
DISPLAY 0.872340 (-75 2000);
PAINT AQUA (-75 2000);
DISPLAY INVISIBLE (-75 2000);
FORCEPROP 2 LAST CDS_LIB mstr_symbols
J 0
(-150 2000);
PAINT ORANGE (-150 2000);
DISPLAY INVISIBLE (-150 2000);
FORCEPROP 1 LAST SIZE 1B
J 0
(-75 1950);
DISPLAY 0.872340 (-75 1950);
PAINT AQUA (-75 1950);
DISPLAY INVISIBLE (-75 1950);
FORCEPROP 1 LAST VOLTAGE 0.0V
J 0
(-195 1957);
DISPLAY 0.340426 (-195 1957);
PAINT SKYBLUE (-195 1957);
DISPLAY INVISIBLE (-195 1957);
FORCEPROP 1 LAST BODY_TYPE PLUMBING
J 0
(-195 1957);
DISPLAY 0.340426 (-195 1957);
PAINT GREEN (-195 1957);
DISPLAY INVISIBLE (-195 1957);
FORCEPROP 1 LAST HDL_POWER GND
J 0
(-150 2150);
DISPLAY 0.872340 (-150 2150);
PAINT GREEN (-150 2150);
DISPLAY INVISIBLE (-150 2150);
FORCEADD GND..1
(-1000 1750);
FORCEPROP 3 LASTPIN (-1000 1800) SIG_NAME GND\g
J 0
(-990 1810);
DISPLAY 0.659574 (-990 1810);
PAINT MONO (-990 1810);
DISPLAY INVISIBLE (-990 1810);
FORCEPROP 1 LAST VOLTAGE 0.0V
J 0
(-1045 1707);
DISPLAY 0.340426 (-1045 1707);
PAINT SKYBLUE (-1045 1707);
DISPLAY INVISIBLE (-1045 1707);
FORCEPROP 2 LAST CDS_LIB mstr_symbols
J 0
(-1000 1750);
PAINT ORANGE (-1000 1750);
DISPLAY INVISIBLE (-1000 1750);
FORCEPROP 1 LAST SIZE 1B
J 0
(-925 1700);
DISPLAY 0.872340 (-925 1700);
PAINT AQUA (-925 1700);
DISPLAY INVISIBLE (-925 1700);
FORCEPROP 1 LAST PATH I110
J 0
(-925 1750);
DISPLAY 0.872340 (-925 1750);
PAINT AQUA (-925 1750);
DISPLAY INVISIBLE (-925 1750);
FORCEPROP 1 LAST BODY_TYPE PLUMBING
J 0
(-1045 1707);
DISPLAY 0.340426 (-1045 1707);
PAINT GREEN (-1045 1707);
DISPLAY INVISIBLE (-1045 1707);
FORCEPROP 1 LAST HDL_POWER GND
J 0
(-1000 1900);
DISPLAY 0.872340 (-1000 1900);
PAINT GREEN (-1000 1900);
DISPLAY INVISIBLE (-1000 1900);
FORCEADD P3V3_STBY..1
(-1000 2750);
FORCEPROP 3 LASTPIN (-1000 2700) SIG_NAME P3V3_STBY\g
J 0
(-990 2710);
DISPLAY 0.659574 (-990 2710);
PAINT MONO (-990 2710);
DISPLAY INVISIBLE (-990 2710);
FORCEPROP 1 LAST VOLTAGE 3.3V
J 0
(-1045 2707);
DISPLAY 0.340426 (-1045 2707);
PAINT SKYBLUE (-1045 2707);
DISPLAY INVISIBLE (-1045 2707);
FORCEPROP 1 LAST PATH I111
J 0
(-955 2752);
DISPLAY 0.340426 (-955 2752);
PAINT GREEN (-955 2752);
DISPLAY INVISIBLE (-955 2752);
FORCEPROP 1 LAST SIZE 1B
J 0
(-955 2772);
DISPLAY 0.340426 (-955 2772);
PAINT GREEN (-955 2772);
DISPLAY INVISIBLE (-955 2772);
FORCEPROP 2 LAST CDS_LIB mstr_symbols
J 0
(-1000 2750);
PAINT ORANGE (-1000 2750);
DISPLAY INVISIBLE (-1000 2750);
FORCEPROP 1 LAST BODY_TYPE PLUMBING
J 0
(-1045 2707);
DISPLAY 0.340426 (-1045 2707);
PAINT GREEN (-1045 2707);
DISPLAY INVISIBLE (-1045 2707);
FORCEPROP 1 LAST HDL_POWER P3V3_STBY
J 0
(-1300 2625);
DISPLAY 0.872340 (-1300 2625);
PAINT ORANGE (-1300 2625);
DISPLAY INVISIBLE (-1300 2625);
FORCEADD RES..2
(-1750 2850);
FORCEPROP 1 LASTPIN (-1750 2750) $PN 2
J 0
(-1745 2760);
DISPLAY 0.617021 (-1745 2760);
PAINT ORANGE (-1745 2760);
FORCEPROP 1 LAST PACK_TYPE 0402
J 0
(-1710 2675);
DISPLAY 0.617021 (-1710 2675);
PAINT SKYBLUE (-1710 2675);
FORCEPROP 1 LASTPIN (-1750 2950) $PN 1
J 0
(-1745 2912);
DISPLAY 0.617021 (-1745 2912);
PAINT ORANGE (-1745 2912);
FORCEPROP 1 LAST TOLERANCE 1%
J 0
(-1705 2875);
DISPLAY 0.617021 (-1705 2875);
PAINT SKYBLUE (-1705 2875);
FORCEPROP 1 LAST LOCATION R8D38
J 0
(-1705 2975);
DISPLAY 0.617021 (-1705 2975);
PAINT AQUA (-1705 2975);
FORCEPROP 1 LAST WATTAGE 1/16W
J 0
(-1710 2825);
DISPLAY 0.617021 (-1710 2825);
PAINT SKYBLUE (-1710 2825);
FORCEPROP 0 LAST NEW_VALUE 511K
J 0
(-1700 2925);
DISPLAY 0.638298 (-1700 2925);
PAINT BROWN (-1700 2925);
DISPLAY BOTH (-1700 2925);
FORCEPROP 0 LAST CONFIG 64.51135.6DL
J 0
(-1700 2725);
DISPLAY 0.638298 (-1700 2725);
PAINT BROWN (-1700 2725);
DISPLAY BOTH (-1700 2725);
FORCEPROP 1 LAST MATERIAL CHIP
J 0
(-1710 2775);
DISPLAY 0.617021 (-1710 2775);
PAINT SKYBLUE (-1710 2775);
FORCEPROP 1 LAST PATH I112
J 0
(-1700 3025);
DISPLAY 0.978723 (-1700 3025);
PAINT WHITE (-1700 3025);
DISPLAY INVISIBLE (-1700 3025);
FORCEPROP 2 LAST CDS_LIB mstr_discrete
J 0
(-1750 2850);
PAINT ORANGE (-1750 2850);
DISPLAY INVISIBLE (-1750 2850);
FORCEPROP 2 LAST ROOM V_SUPER
J 0
(-1700 3025);
DISPLAY 1.021277 (-1700 3025);
PAINT ORANGE (-1700 3025);
DISPLAY INVISIBLE (-1700 3025);
FORCEPROP 2 LAST SEC_TYPE 0402
J 0
(-1700 3075);
DISPLAY 1.021277 (-1700 3075);
PAINT ORANGE (-1700 3075);
DISPLAY INVISIBLE (-1700 3075);
FORCEPROP 2 LAST SEC 1
J 0
(-1700 3075);
PAINT MONO (-1700 3075);
DISPLAY INVISIBLE (-1700 3075);
FORCEPROP 1 LAST VALUE 100.0K
J 0
(-1705 2925);
DISPLAY 0.617021 (-1705 2925);
PAINT SKYBLUE (-1705 2925);
DISPLAY INVISIBLE (-1705 2925);
FORCEPROP 1 LAST PART_NUMBER G21796-010
J 0
(-1710 2725);
DISPLAY 0.617021 (-1710 2725);
PAINT BLUE (-1710 2725);
DISPLAY INVISIBLE (-1710 2725);
FORCEADD RES..2
(-1750 1850);
FORCEPROP 1 LAST MATERIAL CHIP
J 0
(-1710 1775);
DISPLAY 0.617021 (-1710 1775);
PAINT SKYBLUE (-1710 1775);
FORCEPROP 1 LASTPIN (-1750 1950) $PN 1
J 0
(-1745 1912);
DISPLAY 0.617021 (-1745 1912);
PAINT ORANGE (-1745 1912);
FORCEPROP 1 LAST PART_NUMBER G21796-048
J 0
(-1710 1725);
DISPLAY 0.617021 (-1710 1725);
PAINT BLUE (-1710 1725);
FORCEPROP 1 LAST PACK_TYPE 0402
J 0
(-1710 1675);
DISPLAY 0.617021 (-1710 1675);
PAINT SKYBLUE (-1710 1675);
FORCEPROP 1 LASTPIN (-1750 1750) $PN 2
J 0
(-1745 1760);
DISPLAY 0.617021 (-1745 1760);
PAINT ORANGE (-1745 1760);
FORCEPROP 1 LAST TOLERANCE 1%
J 0
(-1705 1875);
DISPLAY 0.617021 (-1705 1875);
PAINT SKYBLUE (-1705 1875);
FORCEPROP 1 LAST VALUE 49.9K
J 0
(-1705 1925);
DISPLAY 0.617021 (-1705 1925);
PAINT SKYBLUE (-1705 1925);
FORCEPROP 1 LAST LOCATION R8D39
J 0
(-1705 1975);
DISPLAY 0.617021 (-1705 1975);
PAINT AQUA (-1705 1975);
FORCEPROP 1 LAST WATTAGE 1/16W
J 0
(-1710 1825);
DISPLAY 0.617021 (-1710 1825);
PAINT SKYBLUE (-1710 1825);
FORCEPROP 2 LAST CDS_LIB mstr_discrete
J 0
(-1750 1850);
PAINT ORANGE (-1750 1850);
DISPLAY INVISIBLE (-1750 1850);
FORCEPROP 2 LAST ROOM V_SUPER
J 0
(-1700 2025);
DISPLAY 1.021277 (-1700 2025);
PAINT ORANGE (-1700 2025);
DISPLAY INVISIBLE (-1700 2025);
FORCEPROP 1 LAST PATH I114
J 0
(-1700 2025);
DISPLAY 0.978723 (-1700 2025);
PAINT WHITE (-1700 2025);
DISPLAY INVISIBLE (-1700 2025);
FORCEPROP 2 LAST SEC_TYPE 0402
J 0
(-1700 2075);
DISPLAY 1.021277 (-1700 2075);
PAINT ORANGE (-1700 2075);
DISPLAY INVISIBLE (-1700 2075);
FORCEPROP 2 LAST SEC 1
J 0
(-1700 2075);
PAINT MONO (-1700 2075);
DISPLAY INVISIBLE (-1700 2075);
FORCEADD RES..2
(-1750 1450);
FORCEPROP 1 LASTPIN (-1750 1350) $PN 2
J 0
(-1745 1360);
DISPLAY 0.617021 (-1745 1360);
PAINT ORANGE (-1745 1360);
FORCEPROP 1 LAST TOLERANCE 1%
J 0
(-1705 1475);
DISPLAY 0.617021 (-1705 1475);
PAINT SKYBLUE (-1705 1475);
FORCEPROP 1 LAST MATERIAL CHIP
J 0
(-1710 1375);
DISPLAY 0.617021 (-1710 1375);
PAINT SKYBLUE (-1710 1375);
FORCEPROP 1 LASTPIN (-1750 1550) $PN 1
J 0
(-1745 1512);
DISPLAY 0.617021 (-1745 1512);
PAINT ORANGE (-1745 1512);
FORCEPROP 1 LAST VALUE 4.75K
J 0
(-1705 1525);
DISPLAY 0.617021 (-1705 1525);
PAINT SKYBLUE (-1705 1525);
FORCEPROP 1 LAST LOCATION R8D37
J 0
(-1705 1575);
DISPLAY 0.617021 (-1705 1575);
PAINT AQUA (-1705 1575);
FORCEPROP 1 LAST PART_NUMBER G21796-072
J 0
(-1710 1325);
DISPLAY 0.617021 (-1710 1325);
PAINT BLUE (-1710 1325);
FORCEPROP 1 LAST PACK_TYPE 0402
J 0
(-1710 1275);
DISPLAY 0.617021 (-1710 1275);
PAINT SKYBLUE (-1710 1275);
FORCEPROP 1 LAST WATTAGE 1/16W
J 0
(-1710 1425);
DISPLAY 0.617021 (-1710 1425);
PAINT SKYBLUE (-1710 1425);
FORCEPROP 2 LAST CDS_LIB mstr_discrete
J 0
(-1750 1450);
PAINT ORANGE (-1750 1450);
DISPLAY INVISIBLE (-1750 1450);
FORCEPROP 2 LAST ROOM V_SUPER
J 0
(-1700 1625);
DISPLAY 1.021277 (-1700 1625);
PAINT ORANGE (-1700 1625);
DISPLAY INVISIBLE (-1700 1625);
FORCEPROP 1 LAST PATH I115
J 0
(-1700 1625);
DISPLAY 0.978723 (-1700 1625);
PAINT WHITE (-1700 1625);
DISPLAY INVISIBLE (-1700 1625);
FORCEPROP 2 LAST SEC_TYPE 0402
J 0
(-1700 1675);
DISPLAY 1.021277 (-1700 1675);
PAINT ORANGE (-1700 1675);
DISPLAY INVISIBLE (-1700 1675);
FORCEPROP 2 LAST SEC 1
J 0
(-1700 1675);
PAINT MONO (-1700 1675);
DISPLAY INVISIBLE (-1700 1675);
FORCEADD P5V..1
(-1750 2050);
FORCEPROP 3 LASTPIN (-1750 2000) SIG_NAME P5V\g
J 0
(-1740 2010);
DISPLAY 0.659574 (-1740 2010);
PAINT MONO (-1740 2010);
DISPLAY INVISIBLE (-1740 2010);
FORCEPROP 1 LAST VOLTAGE 5.0V
J 0
(-1795 2007);
DISPLAY 0.340426 (-1795 2007);
PAINT SKYBLUE (-1795 2007);
DISPLAY INVISIBLE (-1795 2007);
FORCEPROP 1 LAST PATH I116
J 0
(-1705 2052);
DISPLAY 0.340426 (-1705 2052);
PAINT GREEN (-1705 2052);
DISPLAY INVISIBLE (-1705 2052);
FORCEPROP 2 LAST CDS_LIB mstr_symbols
J 0
(-1750 2050);
PAINT ORANGE (-1750 2050);
DISPLAY INVISIBLE (-1750 2050);
FORCEPROP 1 LAST SIZE 1B
J 0
(-1705 2072);
DISPLAY 0.340426 (-1705 2072);
PAINT GREEN (-1705 2072);
DISPLAY INVISIBLE (-1705 2072);
FORCEPROP 1 LAST BODY_TYPE PLUMBING
J 0
(-1795 2007);
DISPLAY 0.340426 (-1795 2007);
PAINT GREEN (-1795 2007);
DISPLAY INVISIBLE (-1795 2007);
FORCEPROP 1 LAST HDL_POWER P5V
J 0
(-2050 1925);
DISPLAY 0.872340 (-2050 1925);
PAINT ORANGE (-2050 1925);
DISPLAY INVISIBLE (-2050 1925);
FORCEADD P12V..1
(-1750 3050);
FORCEPROP 3 LASTPIN (-1750 3000) SIG_NAME P12V\g
J 0
(-1740 3010);
DISPLAY 0.659574 (-1740 3010);
PAINT MONO (-1740 3010);
DISPLAY INVISIBLE (-1740 3010);
FORCEPROP 1 LAST SIZE 1B
J 0
(-1705 3072);
DISPLAY 0.340426 (-1705 3072);
PAINT GREEN (-1705 3072);
DISPLAY INVISIBLE (-1705 3072);
FORCEPROP 2 LAST CDS_LIB mstr_symbols
J 0
(-1750 3050);
PAINT ORANGE (-1750 3050);
DISPLAY INVISIBLE (-1750 3050);
FORCEPROP 1 LAST PATH I117
J 0
(-1705 3052);
DISPLAY 0.340426 (-1705 3052);
PAINT GREEN (-1705 3052);
DISPLAY INVISIBLE (-1705 3052);
FORCEPROP 1 LAST VOLTAGE 12.0V
J 0
(-1795 3007);
DISPLAY 0.340426 (-1795 3007);
PAINT SKYBLUE (-1795 3007);
DISPLAY INVISIBLE (-1795 3007);
FORCEPROP 1 LAST BODY_TYPE PLUMBING
J 0
(-1795 3007);
DISPLAY 0.340426 (-1795 3007);
PAINT GREEN (-1795 3007);
DISPLAY INVISIBLE (-1795 3007);
FORCEPROP 1 LAST HDL_POWER P12V
J 0
(-1950 2900);
DISPLAY 0.872340 (-1950 2900);
PAINT ORANGE (-1950 2900);
DISPLAY INVISIBLE (-1950 2900);
FORCEADD GND..1
(-1750 2175);
FORCEPROP 3 LASTPIN (-1750 2225) SIG_NAME GND\g
J 0
(-1740 2235);
DISPLAY 0.659574 (-1740 2235);
PAINT MONO (-1740 2235);
DISPLAY INVISIBLE (-1740 2235);
FORCEPROP 2 LAST CDS_LIB mstr_symbols
J 0
(-1750 2175);
PAINT ORANGE (-1750 2175);
DISPLAY INVISIBLE (-1750 2175);
FORCEPROP 1 LAST PATH I118
J 0
(-1675 2175);
DISPLAY 0.872340 (-1675 2175);
PAINT AQUA (-1675 2175);
DISPLAY INVISIBLE (-1675 2175);
FORCEPROP 1 LAST SIZE 1B
J 0
(-1675 2125);
DISPLAY 0.872340 (-1675 2125);
PAINT AQUA (-1675 2125);
DISPLAY INVISIBLE (-1675 2125);
FORCEPROP 1 LAST VOLTAGE 0.0V
J 0
(-1795 2132);
DISPLAY 0.340426 (-1795 2132);
PAINT SKYBLUE (-1795 2132);
DISPLAY INVISIBLE (-1795 2132);
FORCEPROP 1 LAST BODY_TYPE PLUMBING
J 0
(-1795 2132);
DISPLAY 0.340426 (-1795 2132);
PAINT GREEN (-1795 2132);
DISPLAY INVISIBLE (-1795 2132);
FORCEPROP 1 LAST HDL_POWER GND
J 0
(-1750 2325);
DISPLAY 0.872340 (-1750 2325);
PAINT GREEN (-1750 2325);
DISPLAY INVISIBLE (-1750 2325);
FORCEADD GND..1
(-1750 1250);
FORCEPROP 3 LASTPIN (-1750 1300) SIG_NAME GND\g
J 0
(-1740 1310);
DISPLAY 0.659574 (-1740 1310);
PAINT MONO (-1740 1310);
DISPLAY INVISIBLE (-1740 1310);
FORCEPROP 1 LAST VOLTAGE 0.0V
J 0
(-1795 1207);
DISPLAY 0.340426 (-1795 1207);
PAINT SKYBLUE (-1795 1207);
DISPLAY INVISIBLE (-1795 1207);
FORCEPROP 1 LAST SIZE 1B
J 0
(-1675 1200);
DISPLAY 0.872340 (-1675 1200);
PAINT AQUA (-1675 1200);
DISPLAY INVISIBLE (-1675 1200);
FORCEPROP 1 LAST PATH I119
J 0
(-1675 1250);
DISPLAY 0.872340 (-1675 1250);
PAINT AQUA (-1675 1250);
DISPLAY INVISIBLE (-1675 1250);
FORCEPROP 2 LAST CDS_LIB mstr_symbols
J 0
(-1750 1250);
PAINT ORANGE (-1750 1250);
DISPLAY INVISIBLE (-1750 1250);
FORCEPROP 1 LAST BODY_TYPE PLUMBING
J 0
(-1795 1207);
DISPLAY 0.340426 (-1795 1207);
PAINT GREEN (-1795 1207);
DISPLAY INVISIBLE (-1795 1207);
FORCEPROP 1 LAST HDL_POWER GND
J 0
(-1750 1400);
DISPLAY 0.872340 (-1750 1400);
PAINT GREEN (-1750 1400);
DISPLAY INVISIBLE (-1750 1400);
FORCEADD RES..2
(50 2650);
FORCEPROP 1 LAST PACK_TYPE 0402
J 0
(90 2475);
DISPLAY 0.617021 (90 2475);
PAINT SKYBLUE (90 2475);
FORCEPROP 1 LAST PART_NUMBER G21796-016
J 0
(90 2525);
DISPLAY 0.617021 (90 2525);
PAINT BLUE (90 2525);
FORCEPROP 1 LASTPIN (50 2550) $PN 2
J 0
(55 2560);
DISPLAY 0.617021 (55 2560);
PAINT ORANGE (55 2560);
FORCEPROP 1 LASTPIN (50 2750) $PN 1
J 0
(55 2712);
DISPLAY 0.617021 (55 2712);
PAINT ORANGE (55 2712);
FORCEPROP 1 LAST LOCATION R8D41
J 0
(95 2775);
DISPLAY 0.617021 (95 2775);
PAINT AQUA (95 2775);
FORCEPROP 1 LAST VALUE 10.0K
J 0
(95 2725);
DISPLAY 0.617021 (95 2725);
PAINT SKYBLUE (95 2725);
FORCEPROP 1 LAST TOLERANCE 1%
J 0
(95 2675);
DISPLAY 0.617021 (95 2675);
PAINT SKYBLUE (95 2675);
FORCEPROP 1 LAST MATERIAL CHIP
J 0
(90 2575);
DISPLAY 0.617021 (90 2575);
PAINT SKYBLUE (90 2575);
FORCEPROP 1 LAST WATTAGE 1/16W
J 0
(90 2625);
DISPLAY 0.617021 (90 2625);
PAINT SKYBLUE (90 2625);
FORCEPROP 2 LAST CDS_LIB mstr_discrete
J 0
(50 2650);
PAINT ORANGE (50 2650);
DISPLAY INVISIBLE (50 2650);
FORCEPROP 2 LAST ROOM V_SUPER
J 0
(100 2825);
DISPLAY 1.021277 (100 2825);
PAINT ORANGE (100 2825);
DISPLAY INVISIBLE (100 2825);
FORCEPROP 1 LAST PATH I120
J 0
(100 2825);
DISPLAY 0.978723 (100 2825);
PAINT WHITE (100 2825);
DISPLAY INVISIBLE (100 2825);
FORCEPROP 2 LAST SEC_TYPE 0402
J 0
(100 2875);
DISPLAY 1.021277 (100 2875);
PAINT ORANGE (100 2875);
DISPLAY INVISIBLE (100 2875);
FORCEPROP 2 LAST SEC 1
J 0
(100 2875);
PAINT MONO (100 2875);
DISPLAY INVISIBLE (100 2875);
FORCEADD RES..2
(250 2000);
FORCEPROP 1 LASTPIN (250 1900) $PN 2
J 0
(255 1910);
DISPLAY 0.617021 (255 1910);
PAINT ORANGE (255 1910);
FORCEPROP 1 LAST WATTAGE 1/16W
J 0
(290 1975);
DISPLAY 0.617021 (290 1975);
PAINT SKYBLUE (290 1975);
FORCEPROP 1 LAST MATERIAL CHIP
J 0
(290 1925);
DISPLAY 0.617021 (290 1925);
PAINT SKYBLUE (290 1925);
FORCEPROP 1 LAST PACK_TYPE 0402
J 0
(290 1825);
DISPLAY 0.617021 (290 1825);
PAINT SKYBLUE (290 1825);
FORCEPROP 1 LASTPIN (250 2100) $PN 1
J 0
(255 2062);
DISPLAY 0.617021 (255 2062);
PAINT ORANGE (255 2062);
FORCEPROP 1 LAST LOCATION R2P18
J 0
(295 2125);
DISPLAY 0.617021 (295 2125);
PAINT AQUA (295 2125);
FORCEPROP 1 LAST VALUE 10.0K
J 0
(295 2075);
DISPLAY 0.617021 (295 2075);
PAINT SKYBLUE (295 2075);
FORCEPROP 1 LAST TOLERANCE 1%
J 0
(295 2025);
DISPLAY 0.617021 (295 2025);
PAINT SKYBLUE (295 2025);
FORCEPROP 1 LAST PART_NUMBER G21796-016
J 0
(290 1875);
DISPLAY 0.617021 (290 1875);
PAINT BLUE (290 1875);
FORCEPROP 2 LAST CDS_LIB mstr_discrete
J 0
(250 2000);
PAINT ORANGE (250 2000);
DISPLAY INVISIBLE (250 2000);
FORCEPROP 2 LAST ROOM V_SUPER
J 0
(300 2175);
DISPLAY 1.021277 (300 2175);
PAINT ORANGE (300 2175);
DISPLAY INVISIBLE (300 2175);
FORCEPROP 1 LAST PATH I121
J 0
(300 2175);
DISPLAY 0.978723 (300 2175);
PAINT WHITE (300 2175);
DISPLAY INVISIBLE (300 2175);
FORCEPROP 2 LAST SEC_TYPE 0402
J 0
(300 2225);
DISPLAY 1.021277 (300 2225);
PAINT ORANGE (300 2225);
DISPLAY INVISIBLE (300 2225);
FORCEPROP 2 LAST SEC 1
J 0
(300 2225);
PAINT MONO (300 2225);
DISPLAY INVISIBLE (300 2225);
FORCEADD RES..2
(750 2200);
FORCEPROP 1 LAST PACK_TYPE 0402
J 0
(790 2025);
DISPLAY 0.617021 (790 2025);
PAINT SKYBLUE (790 2025);
FORCEPROP 1 LASTPIN (750 2100) $PN 2
J 0
(755 2110);
DISPLAY 0.617021 (755 2110);
PAINT ORANGE (755 2110);
FORCEPROP 1 LAST WATTAGE 1/16W
J 0
(790 2175);
DISPLAY 0.617021 (790 2175);
PAINT SKYBLUE (790 2175);
FORCEPROP 1 LAST MATERIAL CHIP
J 0
(790 2125);
DISPLAY 0.617021 (790 2125);
PAINT SKYBLUE (790 2125);
FORCEPROP 1 LAST VALUE 10.0K
J 0
(795 2275);
DISPLAY 0.617021 (795 2275);
PAINT SKYBLUE (795 2275);
FORCEPROP 1 LAST PART_NUMBER G21796-016
J 0
(790 2075);
DISPLAY 0.617021 (790 2075);
PAINT BLUE (790 2075);
FORCEPROP 1 LAST LOCATION R2P21
J 0
(795 2325);
DISPLAY 0.617021 (795 2325);
PAINT AQUA (795 2325);
FORCEPROP 1 LASTPIN (750 2300) $PN 1
J 0
(755 2262);
DISPLAY 0.617021 (755 2262);
PAINT ORANGE (755 2262);
FORCEPROP 1 LAST TOLERANCE 1%
J 0
(795 2225);
DISPLAY 0.617021 (795 2225);
PAINT SKYBLUE (795 2225);
FORCEPROP 2 LAST CDS_LIB mstr_discrete
J 0
(750 2200);
PAINT ORANGE (750 2200);
DISPLAY INVISIBLE (750 2200);
FORCEPROP 2 LAST ROOM V_SUPER
J 0
(800 2375);
DISPLAY 1.021277 (800 2375);
PAINT ORANGE (800 2375);
DISPLAY INVISIBLE (800 2375);
FORCEPROP 1 LAST PATH I122
J 0
(800 2375);
DISPLAY 0.978723 (800 2375);
PAINT WHITE (800 2375);
DISPLAY INVISIBLE (800 2375);
FORCEPROP 2 LAST SEC 1
J 0
(800 2425);
PAINT MONO (800 2425);
DISPLAY INVISIBLE (800 2425);
FORCEPROP 2 LAST SEC_TYPE 0402
J 0
(800 2425);
DISPLAY 1.021277 (800 2425);
PAINT ORANGE (800 2425);
DISPLAY INVISIBLE (800 2425);
FORCEADD P3V3_STBY..1
(50 2850);
FORCEPROP 3 LASTPIN (50 2800) SIG_NAME P3V3_STBY\g
J 0
(60 2810);
DISPLAY 0.659574 (60 2810);
PAINT MONO (60 2810);
DISPLAY INVISIBLE (60 2810);
FORCEPROP 1 LAST VOLTAGE 3.3V
J 0
(5 2807);
DISPLAY 0.340426 (5 2807);
PAINT SKYBLUE (5 2807);
DISPLAY INVISIBLE (5 2807);
FORCEPROP 1 LAST PATH I123
J 0
(95 2852);
DISPLAY 0.340426 (95 2852);
PAINT GREEN (95 2852);
DISPLAY INVISIBLE (95 2852);
FORCEPROP 1 LAST SIZE 1B
J 0
(95 2872);
DISPLAY 0.340426 (95 2872);
PAINT GREEN (95 2872);
DISPLAY INVISIBLE (95 2872);
FORCEPROP 2 LAST CDS_LIB mstr_symbols
J 0
(50 2850);
PAINT ORANGE (50 2850);
DISPLAY INVISIBLE (50 2850);
FORCEPROP 1 LAST BODY_TYPE PLUMBING
J 0
(5 2807);
DISPLAY 0.340426 (5 2807);
PAINT GREEN (5 2807);
DISPLAY INVISIBLE (5 2807);
FORCEPROP 1 LAST HDL_POWER P3V3_STBY
J 0
(-250 2725);
DISPLAY 0.872340 (-250 2725);
PAINT ORANGE (-250 2725);
DISPLAY INVISIBLE (-250 2725);
FORCEADD GND..1
(750 1450);
FORCEPROP 3 LASTPIN (750 1500) SIG_NAME GND\g
J 0
(760 1510);
DISPLAY 0.659574 (760 1510);
PAINT MONO (760 1510);
DISPLAY INVISIBLE (760 1510);
FORCEPROP 1 LAST PATH I125
J 0
(825 1450);
DISPLAY 0.872340 (825 1450);
PAINT AQUA (825 1450);
DISPLAY INVISIBLE (825 1450);
FORCEPROP 1 LAST SIZE 1B
J 0
(825 1400);
DISPLAY 0.872340 (825 1400);
PAINT AQUA (825 1400);
DISPLAY INVISIBLE (825 1400);
FORCEPROP 2 LAST CDS_LIB mstr_symbols
J 0
(750 1450);
PAINT ORANGE (750 1450);
DISPLAY INVISIBLE (750 1450);
FORCEPROP 1 LAST VOLTAGE 0.0V
J 0
(705 1407);
DISPLAY 0.340426 (705 1407);
PAINT SKYBLUE (705 1407);
DISPLAY INVISIBLE (705 1407);
FORCEPROP 1 LAST BODY_TYPE PLUMBING
J 0
(705 1407);
DISPLAY 0.340426 (705 1407);
PAINT GREEN (705 1407);
DISPLAY INVISIBLE (705 1407);
FORCEPROP 1 LAST HDL_POWER GND
J 0
(750 1600);
DISPLAY 0.872340 (750 1600);
PAINT GREEN (750 1600);
DISPLAY INVISIBLE (750 1600);
FORCEADD P3V3_STBY..1
(250 2300);
FORCEPROP 3 LASTPIN (250 2250) SIG_NAME P3V3_STBY\g
J 0
(260 2260);
DISPLAY 0.659574 (260 2260);
PAINT MONO (260 2260);
DISPLAY INVISIBLE (260 2260);
FORCEPROP 1 LAST VOLTAGE 3.3V
J 0
(205 2257);
DISPLAY 0.340426 (205 2257);
PAINT SKYBLUE (205 2257);
DISPLAY INVISIBLE (205 2257);
FORCEPROP 2 LAST CDS_LIB mstr_symbols
J 0
(250 2300);
PAINT ORANGE (250 2300);
DISPLAY INVISIBLE (250 2300);
FORCEPROP 1 LAST SIZE 1B
J 0
(295 2322);
DISPLAY 0.340426 (295 2322);
PAINT GREEN (295 2322);
DISPLAY INVISIBLE (295 2322);
FORCEPROP 1 LAST PATH I126
J 0
(295 2302);
DISPLAY 0.340426 (295 2302);
PAINT GREEN (295 2302);
DISPLAY INVISIBLE (295 2302);
FORCEPROP 1 LAST BODY_TYPE PLUMBING
J 0
(205 2257);
DISPLAY 0.340426 (205 2257);
PAINT GREEN (205 2257);
DISPLAY INVISIBLE (205 2257);
FORCEPROP 1 LAST HDL_POWER P3V3_STBY
J 0
(-50 2175);
DISPLAY 0.872340 (-50 2175);
PAINT ORANGE (-50 2175);
DISPLAY INVISIBLE (-50 2175);
FORCEADD P3V3_STBY..1
(750 2600);
FORCEPROP 3 LASTPIN (750 2550) SIG_NAME P3V3_STBY\g
J 0
(760 2560);
DISPLAY 0.659574 (760 2560);
PAINT MONO (760 2560);
DISPLAY INVISIBLE (760 2560);
FORCEPROP 1 LAST VOLTAGE 3.3V
J 0
(705 2557);
DISPLAY 0.340426 (705 2557);
PAINT SKYBLUE (705 2557);
DISPLAY INVISIBLE (705 2557);
FORCEPROP 1 LAST PATH I127
J 0
(795 2602);
DISPLAY 0.340426 (795 2602);
PAINT GREEN (795 2602);
DISPLAY INVISIBLE (795 2602);
FORCEPROP 2 LAST CDS_LIB mstr_symbols
J 0
(750 2600);
PAINT ORANGE (750 2600);
DISPLAY INVISIBLE (750 2600);
FORCEPROP 1 LAST SIZE 1B
J 0
(795 2622);
DISPLAY 0.340426 (795 2622);
PAINT GREEN (795 2622);
DISPLAY INVISIBLE (795 2622);
FORCEPROP 1 LAST BODY_TYPE PLUMBING
J 0
(705 2557);
DISPLAY 0.340426 (705 2557);
PAINT GREEN (705 2557);
DISPLAY INVISIBLE (705 2557);
FORCEPROP 1 LAST HDL_POWER P3V3_STBY
J 0
(450 2475);
DISPLAY 0.872340 (450 2475);
PAINT ORANGE (450 2475);
DISPLAY INVISIBLE (450 2475);
FORCEADD DIODE..3
(1050 3400);
FORCEPROP 1 LASTPIN (950 3400) $PN 1
J 2
(985 3410);
DISPLAY 0.617021 (985 3410);
PAINT AQUA (985 3410);
FORCEPROP 1 LAST LOCATION CR8E1
J 0
(1023 3556);
DISPLAY 0.617021 (1023 3556);
PAINT AQUA (1023 3556);
FORCEPROP 1 LAST VALUE BAT54WS
J 0
(1025 3275);
DISPLAY 0.617021 (1025 3275);
PAINT SKYBLUE (1025 3275);
FORCEPROP 1 LAST PACK_TYPE SMLF
J 0
(1025 3160);
DISPLAY 0.617021 (1025 3160);
PAINT SKYBLUE (1025 3160);
FORCEPROP 1 LAST MATERIAL IC
J 0
(1025 3222);
DISPLAY 0.617021 (1025 3222);
PAINT SKYBLUE (1025 3222);
FORCEPROP 1 LASTPIN (1150 3400) $PN 2
J 0
(1125 3410);
DISPLAY 0.617021 (1125 3410);
PAINT AQUA (1125 3410);
FORCEPROP 1 LAST PART_NUMBER C73510-001
J 0
(1025 3500);
DISPLAY 0.617021 (1025 3500);
PAINT BLUE (1025 3500);
FORCEPROP 2 LAST CDS_LIB mstr_discrete
J 0
(1050 3400);
PAINT ORANGE (1050 3400);
DISPLAY INVISIBLE (1050 3400);
FORCEPROP 1 LAST PATH I128
J 0
(1030 3610);
DISPLAY 0.978723 (1030 3610);
PAINT PINK (1030 3610);
DISPLAY INVISIBLE (1030 3610);
FORCEPROP 2 LAST SEC_TYPE SMLF
J 0
(1050 3675);
DISPLAY 1.021277 (1050 3675);
PAINT ORANGE (1050 3675);
DISPLAY INVISIBLE (1050 3675);
FORCEPROP 2 LAST SEC 1
J 0
(1050 3675);
PAINT MONO (1050 3675);
DISPLAY INVISIBLE (1050 3675);
FORCEADD FET_N..8
(750 1750);
FORCEPROP 1 LAST MATERIAL FET
J 0
(950 1650);
DISPLAY 0.617021 (950 1650);
PAINT SKYBLUE (950 1650);
FORCEPROP 1 LAST LOCATION Q1P2
J 0
(950 1750);
DISPLAY 0.617021 (950 1750);
PAINT AQUA (950 1750);
FORCEPROP 1 LAST VALUE 2N7002
J 0
(950 1700);
DISPLAY 0.617021 (950 1700);
PAINT SKYBLUE (950 1700);
FORCEPROP 1 LAST PART_NUMBER C79254-001
J 0
(950 1550);
DISPLAY 0.617021 (950 1550);
PAINT BLUE (950 1550);
FORCEPROP 1 LAST PACK_TYPE SOT23LF
J 0
(950 1600);
DISPLAY 0.978723 (950 1600);
PAINT SKYBLUE (950 1600);
DISPLAY INVISIBLE (950 1600);
FORCEPROP 0 LAST ROOM HOT_SWAP
J 0
(950 1850);
DISPLAY 1.021277 (950 1850);
PAINT ORANGE (950 1850);
DISPLAY INVISIBLE (950 1850);
FORCEPROP 1 LAST PATH I129
J 0
(950 1800);
DISPLAY 0.978723 (950 1800);
PAINT BLUE (950 1800);
DISPLAY INVISIBLE (950 1800);
FORCEPROP 2 LAST CDS_LIB mstr_discrete
J 0
(750 1750);
PAINT MONO (750 1750);
DISPLAY INVISIBLE (750 1750);
FORCEPROP 1 LASTPIN (750 1550) $PN 2
J 2
(808 1550);
DISPLAY 0.872340 (808 1550);
PAINT WHITE (808 1550);
DISPLAY INVISIBLE (808 1550);
FORCEPROP 1 LASTPIN (750 1950) $PN 3
J 2
(803 1915);
DISPLAY 0.872340 (803 1915);
PAINT WHITE (803 1915);
DISPLAY INVISIBLE (803 1915);
FORCEPROP 1 LASTPIN (550 1650) $PN 1
J 2
(553 1665);
DISPLAY 0.872340 (553 1665);
PAINT WHITE (553 1665);
DISPLAY INVISIBLE (553 1665);
FORCEADD RES..2
(-1750 2400);
FORCEPROP 1 LAST TOLERANCE 1%
J 0
(-1705 2425);
DISPLAY 0.617021 (-1705 2425);
PAINT SKYBLUE (-1705 2425);
FORCEPROP 1 LAST VALUE 20.0K
J 0
(-1705 2475);
DISPLAY 0.617021 (-1705 2475);
PAINT SKYBLUE (-1705 2475);
FORCEPROP 1 LASTPIN (-1750 2300) $PN 2
J 0
(-1745 2310);
DISPLAY 0.617021 (-1745 2310);
PAINT ORANGE (-1745 2310);
FORCEPROP 1 LAST MATERIAL CHIP
J 0
(-1710 2325);
DISPLAY 0.617021 (-1710 2325);
PAINT SKYBLUE (-1710 2325);
FORCEPROP 1 LAST WATTAGE 1/16W
J 0
(-1710 2375);
DISPLAY 0.617021 (-1710 2375);
PAINT SKYBLUE (-1710 2375);
FORCEPROP 1 LASTPIN (-1750 2500) $PN 1
J 0
(-1745 2462);
DISPLAY 0.617021 (-1745 2462);
PAINT ORANGE (-1745 2462);
FORCEPROP 1 LAST PACK_TYPE 0402
J 0
(-1710 2225);
DISPLAY 0.617021 (-1710 2225);
PAINT SKYBLUE (-1710 2225);
FORCEPROP 1 LAST PART_NUMBER G21796-040
J 0
(-1710 2275);
DISPLAY 0.617021 (-1710 2275);
PAINT BLUE (-1710 2275);
FORCEPROP 1 LAST LOCATION R8D40
J 0
(-1705 2525);
DISPLAY 0.617021 (-1705 2525);
PAINT AQUA (-1705 2525);
FORCEPROP 1 LAST PATH I130
J 0
(-1700 2575);
DISPLAY 0.978723 (-1700 2575);
PAINT WHITE (-1700 2575);
DISPLAY INVISIBLE (-1700 2575);
FORCEPROP 2 LAST ROOM SB
J 0
(-1705 2475);
DISPLAY 1.361702 (-1705 2475);
PAINT ORANGE (-1705 2475);
DISPLAY INVISIBLE (-1705 2475);
FORCEPROP 2 LAST BOM_COST SB
R 3
J 0
(-1575 2350);
PAINT ORANGE (-1575 2350);
DISPLAY INVISIBLE (-1575 2350);
FORCEPROP 2 LAST CDS_LIB mstr_discrete
J 0
(-1750 2400);
PAINT ORANGE (-1750 2400);
DISPLAY INVISIBLE (-1750 2400);
FORCEPROP 2 LAST SEC_TYPE 0402
J 0
(-1700 2625);
DISPLAY 1.021277 (-1700 2625);
PAINT ORANGE (-1700 2625);
DISPLAY INVISIBLE (-1700 2625);
FORCEPROP 2 LAST SEC 1
J 0
(-1700 2625);
DISPLAY 0.680851 (-1700 2625);
PAINT MONO (-1700 2625);
DISPLAY INVISIBLE (-1700 2625);
FORCEPROP 2 LAST CDS_LOCATION R8D40
J 0
(-1705 2525);
DISPLAY 0.617021 (-1705 2525);
PAINT AQUA (-1705 2525);
DISPLAY INVISIBLE (-1705 2525);
FORCEADD GND..1
(-2200 4250);
FORCEPROP 3 LASTPIN (-2200 4300) SIG_NAME GND\g
J 0
(-2190 4310);
DISPLAY 0.659574 (-2190 4310);
PAINT MONO (-2190 4310);
DISPLAY INVISIBLE (-2190 4310);
FORCEPROP 2 LAST ROOM BATTERY_CIRCUIT
J 0
(-2525 4325);
DISPLAY 0.702128 (-2525 4325);
PAINT ORANGE (-2525 4325);
DISPLAY INVISIBLE (-2525 4325);
FORCEPROP 1 LAST PATH I43
J 0
(-2125 4250);
DISPLAY 1.170213 (-2125 4250);
PAINT GREEN (-2125 4250);
DISPLAY INVISIBLE (-2125 4250);
FORCEPROP 2 LAST CDS_LIB mstr_symbols
J 0
(-2200 4250);
DISPLAY 1.319149 (-2200 4250);
PAINT ORANGE (-2200 4250);
DISPLAY INVISIBLE (-2200 4250);
FORCEPROP 1 LAST SIZE 1B
J 0
(-2125 4200);
DISPLAY 0.702128 (-2125 4200);
PAINT GREEN (-2125 4200);
DISPLAY INVISIBLE (-2125 4200);
FORCEPROP 1 LAST VOLTAGE 0
J 0
(-2200 4250);
PAINT SKYBLUE (-2200 4250);
DISPLAY INVISIBLE (-2200 4250);
FORCEPROP 1 LAST BODY_TYPE PLUMBING
J 0
(-2245 4207);
DISPLAY 0.340426 (-2245 4207);
PAINT GREEN (-2245 4207);
DISPLAY INVISIBLE (-2245 4207);
FORCEPROP 1 LAST HDL_POWER GND
J 0
(-2200 4400);
DISPLAY 0.702128 (-2200 4400);
PAINT GREEN (-2200 4400);
DISPLAY INVISIBLE (-2200 4400);
FORCEADD OFFPAGE..2
(-2800 4300);
FORCEPROP 2 LAST $XR0 169 
J 0
(-2611 4300);
DISPLAY 0.638298 (-2611 4300);
PAINT MONO (-2611 4300);
FORCEPROP 2 LAST CDS_LIB mstr_standard
J 0
(-2800 4300);
DISPLAY 1.148936 (-2800 4300);
PAINT ORANGE (-2800 4300);
DISPLAY INVISIBLE (-2800 4300);
FORCEPROP 2 LAST ROOM BATTERY_CIRCUIT
J 0
(-2600 4350);
DISPLAY 0.702128 (-2600 4350);
PAINT ORANGE (-2600 4350);
DISPLAY INVISIBLE (-2600 4350);
FORCEPROP 2 LAST PATH I45
J 0
(-2600 4350);
PAINT MONO (-2600 4350);
DISPLAY INVISIBLE (-2600 4350);
FORCEPROP 1 LAST OFFPAGE TRUE
J 0
(-2475 4175);
PAINT GREEN (-2475 4175);
DISPLAY INVISIBLE (-2475 4175);
FORCEPROP 1 LAST COMMENT_BODY TRUE
J 0
(-2845 4205);
DISPLAY 0.702128 (-2845 4205);
PAINT GREEN (-2845 4205);
DISPLAY INVISIBLE (-2845 4205);
FORCEADD RES..1
(-3650 4550);
FORCEPROP 1 LASTPIN (-3750 4550) $PN 1
J 0
(-3738 4562);
DISPLAY 0.617021 (-3738 4562);
PAINT MONO (-3738 4562);
FORCEPROP 1 LAST WATTAGE 1/16W
J 2
(-3675 4400);
DISPLAY 0.617021 (-3675 4400);
PAINT SKYBLUE (-3675 4400);
FORCEPROP 1 LAST TOLERANCE 1%
J 0
(-3650 4450);
DISPLAY 0.617021 (-3650 4450);
PAINT SKYBLUE (-3650 4450);
FORCEPROP 1 LAST VALUE 1.00K
J 2
(-3675 4450);
DISPLAY 0.617021 (-3675 4450);
PAINT SKYBLUE (-3675 4450);
FORCEPROP 1 LASTPIN (-3550 4550) $PN 2
J 0
(-3588 4562);
DISPLAY 0.617021 (-3588 4562);
PAINT MONO (-3588 4562);
FORCEPROP 1 LAST MATERIAL CHIP
J 0
(-3650 4400);
DISPLAY 0.617021 (-3650 4400);
PAINT SKYBLUE (-3650 4400);
FORCEPROP 1 LAST PART_NUMBER G21796-026
J 0
(-3825 4650);
DISPLAY 0.617021 (-3825 4650);
PAINT BLUE (-3825 4650);
FORCEPROP 1 LAST PACK_TYPE 0402
J 0
(-3500 4400);
DISPLAY 0.617021 (-3500 4400);
PAINT SKYBLUE (-3500 4400);
FORCEPROP 1 LAST LOCATION R2U43
J 0
(-3700 4600);
DISPLAY 0.617021 (-3700 4600);
PAINT AQUA (-3700 4600);
FORCEPROP 2 LAST CDS_LIB mstr_discrete
J 0
(-3650 4550);
DISPLAY 1.319149 (-3650 4550);
PAINT ORANGE (-3650 4550);
DISPLAY INVISIBLE (-3650 4550);
FORCEPROP 2 LAST CDS_LOCATION R2U43
J 0
(-3700 4600);
DISPLAY 0.617021 (-3700 4600);
PAINT AQUA (-3700 4600);
DISPLAY INVISIBLE (-3700 4600);
FORCEPROP 2 LAST BOM_COST SB
J 0
(-3825 4700);
PAINT MONO (-3825 4700);
DISPLAY INVISIBLE (-3825 4700);
FORCEPROP 2 LAST SEC_TYPE 0402
J 0
(-3700 4775);
DISPLAY 1.021277 (-3700 4775);
PAINT ORANGE (-3700 4775);
DISPLAY INVISIBLE (-3700 4775);
FORCEPROP 2 LAST SEC 1
J 0
(-3700 4775);
DISPLAY 0.680851 (-3700 4775);
PAINT MONO (-3700 4775);
DISPLAY INVISIBLE (-3700 4775);
FORCEPROP 1 LAST PATH I46
J 0
(-3700 4700);
DISPLAY 1.319149 (-3700 4700);
PAINT GREEN (-3700 4700);
DISPLAY INVISIBLE (-3700 4700);
FORCEPROP 2 LAST ROOM SB_VRD
J 0
(-3700 4700);
DISPLAY 0.702128 (-3700 4700);
PAINT ORANGE (-3700 4700);
DISPLAY INVISIBLE (-3700 4700);
FORCEADD BATTERY..1
(-4375 4200);
FORCEPROP 1 LAST PART_NUMBER 202168-001
J 1
(-4375 4125);
DISPLAY 0.617021 (-4375 4125);
PAINT BLUE (-4375 4125);
FORCEPROP 1 LAST LOCATION BT8G1
J 0
(-4420 4263);
DISPLAY 0.617021 (-4420 4263);
PAINT AQUA (-4420 4263);
FORCEPROP 2 LAST BOM_COST SB
J 0
(-4400 4300);
PAINT MONO (-4400 4300);
DISPLAY INVISIBLE (-4400 4300);
FORCEPROP 2 LAST CDS_LIB mstr_misc
J 0
(-4375 4200);
DISPLAY 1.319149 (-4375 4200);
PAINT ORANGE (-4375 4200);
DISPLAY INVISIBLE (-4375 4200);
FORCEPROP 2 LAST CDS_LOCATION BT8G1
J 0
(-4420 4263);
DISPLAY 0.617021 (-4420 4263);
PAINT AQUA (-4420 4263);
DISPLAY INVISIBLE (-4420 4263);
FORCEPROP 1 LAST PACK_TYPE PLCLF
J 0
(-4420 4325);
PAINT SKYBLUE (-4420 4325);
DISPLAY INVISIBLE (-4420 4325);
FORCEPROP 2 LAST ROOM SB_VRD
J 0
(-4400 4325);
DISPLAY 0.702128 (-4400 4325);
PAINT ORANGE (-4400 4325);
DISPLAY INVISIBLE (-4400 4325);
FORCEPROP 1 LAST PATH I47
J 0
(-4425 4370);
DISPLAY 1.170213 (-4425 4370);
PAINT GREEN (-4425 4370);
DISPLAY INVISIBLE (-4425 4370);
FORCEADD VERT_BATT_3PIN..1
(-4800 4550);
FORCEPROP 2 LASTPIN (-4950 4550) $PN 3
J 2
(-4960 4560);
DISPLAY 0.617021 (-4960 4560);
PAINT ORANGE (-4960 4560);
FORCEPROP 1 LAST PART_NUMBER C68619-005
J 0
(-4950 4400);
DISPLAY 0.617021 (-4950 4400);
PAINT BLUE (-4950 4400);
FORCEPROP 2 LASTPIN (-4650 4500) $PN 2
J 0
(-4640 4510);
DISPLAY 0.617021 (-4640 4510);
PAINT ORANGE (-4640 4510);
FORCEPROP 2 LASTPIN (-4650 4600) $PN 1
J 0
(-4640 4610);
DISPLAY 0.617021 (-4640 4610);
PAINT ORANGE (-4640 4610);
FORCEPROP 1 LAST MATERIAL 3PVERT
J 0
(-4950 4650);
DISPLAY 0.617021 (-4950 4650);
PAINT SKYBLUE (-4950 4650);
FORCEPROP 1 LAST LOCATION XBT8G1
J 0
(-4950 4700);
DISPLAY 0.617021 (-4950 4700);
PAINT AQUA (-4950 4700);
FORCEPROP 2 LAST CDS_LIB mstr_discrete
J 0
(-4800 4550);
PAINT ORANGE (-4800 4550);
DISPLAY INVISIBLE (-4800 4550);
FORCEPROP 1 LAST PATH I51
J 0
(-4650 4450);
DISPLAY 0.872340 (-4650 4450);
PAINT WHITE (-4650 4450);
DISPLAY INVISIBLE (-4650 4450);
FORCEPROP 0 LAST ROOM SB_VRD
J 0
(-4950 4900);
DISPLAY 1.382979 (-4950 4900);
PAINT ORANGE (-4950 4900);
DISPLAY INVISIBLE (-4950 4900);
FORCEPROP 2 LAST SEC_TYPE PIP
J 0
(-4950 4750);
DISPLAY 1.021277 (-4950 4750);
PAINT ORANGE (-4950 4750);
DISPLAY INVISIBLE (-4950 4750);
FORCEPROP 2 LAST SEC 1
J 0
(-4950 4750);
DISPLAY 0.680851 (-4950 4750);
PAINT MONO (-4950 4750);
DISPLAY INVISIBLE (-4950 4750);
FORCEPROP 2 LAST CDS_LOCATION XBT8G1
J 0
(-4950 4700);
DISPLAY 0.617021 (-4950 4700);
PAINT AQUA (-4950 4700);
DISPLAY INVISIBLE (-4950 4700);
FORCEPROP 1 LAST PACK_TYPE PIP
J 0
(-4950 4750);
DISPLAY 0.872340 (-4950 4750);
PAINT SKYBLUE (-4950 4750);
DISPLAY INVISIBLE (-4950 4750);
FORCEADD GND..1
(-5050 4250);
FORCEPROP 3 LASTPIN (-5050 4300) SIG_NAME GND\g
J 0
(-5040 4310);
DISPLAY 0.659574 (-5040 4310);
PAINT MONO (-5040 4310);
DISPLAY INVISIBLE (-5040 4310);
FORCEPROP 2 LAST ROOM SB
J 0
(-5200 4325);
DISPLAY 0.702128 (-5200 4325);
PAINT ORANGE (-5200 4325);
DISPLAY INVISIBLE (-5200 4325);
FORCEPROP 1 LAST SIZE 1B
J 0
(-4975 4200);
DISPLAY 0.702128 (-4975 4200);
PAINT GREEN (-4975 4200);
DISPLAY INVISIBLE (-4975 4200);
FORCEPROP 1 LAST VOLTAGE 0
J 0
(-5050 4250);
PAINT SKYBLUE (-5050 4250);
DISPLAY INVISIBLE (-5050 4250);
FORCEPROP 2 LAST CDS_LIB mstr_symbols
J 0
(-5050 4250);
DISPLAY 1.319149 (-5050 4250);
PAINT ORANGE (-5050 4250);
DISPLAY INVISIBLE (-5050 4250);
FORCEPROP 1 LAST PATH I52
J 0
(-4975 4250);
DISPLAY 1.212766 (-4975 4250);
PAINT AQUA (-4975 4250);
DISPLAY INVISIBLE (-4975 4250);
FORCEPROP 1 LAST BODY_TYPE PLUMBING
J 0
(-5095 4207);
DISPLAY 0.340426 (-5095 4207);
PAINT GREEN (-5095 4207);
DISPLAY INVISIBLE (-5095 4207);
FORCEPROP 1 LAST HDL_POWER GND
J 0
(-5050 4400);
DISPLAY 0.702128 (-5050 4400);
PAINT GREEN (-5050 4400);
DISPLAY INVISIBLE (-5050 4400);
FORCEADD DIODE2A_DUAL..1
(-2700 4650);
FORCEPROP 2 LASTPIN (-2850 4550) $PN 2
J 2
(-2860 4560);
DISPLAY 0.617021 (-2860 4560);
PAINT MONO (-2860 4560);
FORCEPROP 2 LASTPIN (-2850 4750) $PN 1
J 2
(-2860 4760);
DISPLAY 0.617021 (-2860 4760);
PAINT MONO (-2860 4760);
FORCEPROP 1 LAST LOCATION CR2U1
J 0
(-2850 4850);
DISPLAY 0.617021 (-2850 4850);
PAINT AQUA (-2850 4850);
FORCEPROP 1 LAST MATERIAL DIO
J 2
(-2725 4625);
DISPLAY 0.617021 (-2725 4625);
PAINT SKYBLUE (-2725 4625);
FORCEPROP 1 LAST PACK_TYPE SMLF
J 0
(-2600 4525);
DISPLAY 0.617021 (-2600 4525);
PAINT SKYBLUE (-2600 4525);
FORCEPROP 1 LAST VALUE BAS70-05
J 2
(-2400 4575);
DISPLAY 0.617021 (-2400 4575);
PAINT SKYBLUE (-2400 4575);
FORCEPROP 1 LAST PART_NUMBER C90169-001
J 0
(-2850 4900);
DISPLAY 0.617021 (-2850 4900);
PAINT BLUE (-2850 4900);
FORCEPROP 2 LASTPIN (-2550 4650) $PN 3
J 0
(-2540 4660);
DISPLAY 0.617021 (-2540 4660);
PAINT MONO (-2540 4660);
FORCEPROP 2 LAST SEC_TYPE SMLF
J 0
(-2850 5000);
DISPLAY 1.127660 (-2850 5000);
PAINT MONO (-2850 5000);
DISPLAY INVISIBLE (-2850 5000);
FORCEPROP 2 LAST SEC 1
J 0
(-2850 5000);
DISPLAY 0.936170 (-2850 5000);
PAINT MONO (-2850 5000);
DISPLAY INVISIBLE (-2850 5000);
FORCEPROP 2 LAST CDS_LOCATION CR2U1
J 0
(-2850 4850);
DISPLAY 0.617021 (-2850 4850);
PAINT AQUA (-2850 4850);
DISPLAY INVISIBLE (-2850 4850);
FORCEPROP 1 LAST PATH I53
J 0
(-2850 4950);
DISPLAY 1.361702 (-2850 4950);
PAINT BLUE (-2850 4950);
DISPLAY INVISIBLE (-2850 4950);
FORCEPROP 2 LAST ROOM SB_VRD
J 0
(-2850 4950);
DISPLAY 1.404255 (-2850 4950);
PAINT ORANGE (-2850 4950);
DISPLAY INVISIBLE (-2850 4950);
FORCEPROP 2 LAST CDS_LIB mstr_discrete
J 0
(-2700 4650);
DISPLAY 1.319149 (-2700 4650);
PAINT ORANGE (-2700 4650);
DISPLAY INVISIBLE (-2700 4650);
FORCEADD P3V3_STBY..1
(-3250 4975);
FORCEPROP 3 LASTPIN (-3250 4925) SIG_NAME P3V3_STBY\g
J 0
(-3240 4935);
DISPLAY 0.659574 (-3240 4935);
PAINT MONO (-3240 4935);
DISPLAY INVISIBLE (-3240 4935);
FORCEPROP 1 LAST VOLTAGE 3.3V
J 0
(-3295 4932);
DISPLAY 0.340426 (-3295 4932);
PAINT SKYBLUE (-3295 4932);
DISPLAY INVISIBLE (-3295 4932);
FORCEPROP 1 LAST SIZE 1B
J 0
(-3205 4997);
DISPLAY 0.340426 (-3205 4997);
PAINT GREEN (-3205 4997);
DISPLAY INVISIBLE (-3205 4997);
FORCEPROP 2 LAST CDS_LIB mstr_symbols
J 0
(-3250 4975);
PAINT ORANGE (-3250 4975);
DISPLAY INVISIBLE (-3250 4975);
FORCEPROP 1 LAST PATH I54
J 0
(-3205 4977);
DISPLAY 0.340426 (-3205 4977);
PAINT GREEN (-3205 4977);
DISPLAY INVISIBLE (-3205 4977);
FORCEPROP 1 LAST BODY_TYPE PLUMBING
J 0
(-3295 4932);
DISPLAY 0.340426 (-3295 4932);
PAINT GREEN (-3295 4932);
DISPLAY INVISIBLE (-3295 4932);
FORCEPROP 1 LAST HDL_POWER P3V3_STBY
J 0
(-3550 4850);
DISPLAY 0.872340 (-3550 4850);
PAINT ORANGE (-3550 4850);
DISPLAY INVISIBLE (-3550 4850);
FORCEADD P3V3_STBY..1
(-25 5000);
FORCEPROP 3 LASTPIN (-25 4950) SIG_NAME P3V3_STBY\g
J 0
(-15 4960);
DISPLAY 0.659574 (-15 4960);
PAINT MONO (-15 4960);
DISPLAY INVISIBLE (-15 4960);
FORCEPROP 2 LAST CDS_LIB mstr_symbols
J 0
(-25 5000);
PAINT ORANGE (-25 5000);
DISPLAY INVISIBLE (-25 5000);
FORCEPROP 1 LAST VOLTAGE 3.3V
J 0
(-70 4957);
DISPLAY 0.340426 (-70 4957);
PAINT SKYBLUE (-70 4957);
DISPLAY INVISIBLE (-70 4957);
FORCEPROP 1 LAST PATH I56
J 0
(20 5002);
DISPLAY 0.340426 (20 5002);
PAINT GREEN (20 5002);
DISPLAY INVISIBLE (20 5002);
FORCEPROP 1 LAST SIZE 1B
J 0
(20 5022);
DISPLAY 0.340426 (20 5022);
PAINT GREEN (20 5022);
DISPLAY INVISIBLE (20 5022);
FORCEPROP 1 LAST BODY_TYPE PLUMBING
J 0
(-70 4957);
DISPLAY 0.340426 (-70 4957);
PAINT GREEN (-70 4957);
DISPLAY INVISIBLE (-70 4957);
FORCEPROP 1 LAST HDL_POWER P3V3_STBY
J 0
(-325 4875);
DISPLAY 0.872340 (-325 4875);
PAINT ORANGE (-325 4875);
DISPLAY INVISIBLE (-325 4875);
FORCEADD P12V_STBY..1
(-525 5000);
FORCEPROP 3 LASTPIN (-525 4950) SIG_NAME P12V_STBY\g
J 0
(-515 4960);
DISPLAY 0.659574 (-515 4960);
PAINT MONO (-515 4960);
DISPLAY INVISIBLE (-515 4960);
FORCEPROP 2 LAST CDS_LIB mstr_symbols
J 0
(-525 5000);
PAINT ORANGE (-525 5000);
DISPLAY INVISIBLE (-525 5000);
FORCEPROP 1 LAST VOLTAGE 12.0V
J 0
(-570 4957);
DISPLAY 0.340426 (-570 4957);
PAINT SKYBLUE (-570 4957);
DISPLAY INVISIBLE (-570 4957);
FORCEPROP 1 LAST PATH I57
J 0
(-480 5002);
DISPLAY 0.340426 (-480 5002);
PAINT GREEN (-480 5002);
DISPLAY INVISIBLE (-480 5002);
FORCEPROP 1 LAST SIZE 1B
J 0
(-480 5022);
DISPLAY 0.340426 (-480 5022);
PAINT GREEN (-480 5022);
DISPLAY INVISIBLE (-480 5022);
FORCEPROP 1 LAST BODY_TYPE PLUMBING
J 0
(-570 4957);
DISPLAY 0.340426 (-570 4957);
PAINT GREEN (-570 4957);
DISPLAY INVISIBLE (-570 4957);
FORCEPROP 1 LAST HDL_POWER P12V_STBY
J 0
(-825 4875);
DISPLAY 0.872340 (-825 4875);
PAINT ORANGE (-825 4875);
DISPLAY INVISIBLE (-825 4875);
FORCEADD P3V3_STBY..1
(1325 4900);
FORCEPROP 3 LASTPIN (1325 4850) SIG_NAME P3V3_STBY\g
J 0
(1335 4860);
DISPLAY 0.659574 (1335 4860);
PAINT MONO (1335 4860);
DISPLAY INVISIBLE (1335 4860);
FORCEPROP 1 LAST VOLTAGE 3.3V
J 0
(1280 4857);
DISPLAY 0.340426 (1280 4857);
PAINT SKYBLUE (1280 4857);
DISPLAY INVISIBLE (1280 4857);
FORCEPROP 1 LAST PATH I58
J 0
(1370 4902);
DISPLAY 0.340426 (1370 4902);
PAINT GREEN (1370 4902);
DISPLAY INVISIBLE (1370 4902);
FORCEPROP 1 LAST SIZE 1B
J 0
(1370 4922);
DISPLAY 0.340426 (1370 4922);
PAINT GREEN (1370 4922);
DISPLAY INVISIBLE (1370 4922);
FORCEPROP 2 LAST CDS_LIB mstr_symbols
J 0
(1325 4900);
PAINT ORANGE (1325 4900);
DISPLAY INVISIBLE (1325 4900);
FORCEPROP 1 LAST BODY_TYPE PLUMBING
J 0
(1280 4857);
DISPLAY 0.340426 (1280 4857);
PAINT GREEN (1280 4857);
DISPLAY INVISIBLE (1280 4857);
FORCEPROP 1 LAST HDL_POWER P3V3_STBY
J 0
(1025 4775);
DISPLAY 0.872340 (1025 4775);
PAINT ORANGE (1025 4775);
DISPLAY INVISIBLE (1025 4775);
FORCEADD RES..2
(1325 4650);
FORCEPROP 1 LAST PACK_TYPE 0402
J 0
(1365 4475);
DISPLAY 0.617021 (1365 4475);
PAINT SKYBLUE (1365 4475);
FORCEPROP 1 LAST MATERIAL CHIP
J 0
(1365 4575);
DISPLAY 0.617021 (1365 4575);
PAINT SKYBLUE (1365 4575);
FORCEPROP 1 LASTPIN (1325 4550) $PN 2
J 0
(1330 4560);
DISPLAY 0.617021 (1330 4560);
PAINT ORANGE (1330 4560);
FORCEPROP 1 LASTPIN (1325 4750) $PN 1
J 0
(1330 4712);
DISPLAY 0.617021 (1330 4712);
PAINT ORANGE (1330 4712);
FORCEPROP 1 LAST LOCATION R3P44
J 0
(1370 4775);
DISPLAY 0.617021 (1370 4775);
PAINT AQUA (1370 4775);
FORCEPROP 1 LAST TOLERANCE 1%
J 0
(1370 4675);
DISPLAY 0.617021 (1370 4675);
PAINT SKYBLUE (1370 4675);
FORCEPROP 1 LAST VALUE 4.75K
J 0
(1370 4725);
DISPLAY 0.617021 (1370 4725);
PAINT SKYBLUE (1370 4725);
FORCEPROP 1 LAST WATTAGE 1/16W
J 0
(1365 4625);
DISPLAY 0.617021 (1365 4625);
PAINT SKYBLUE (1365 4625);
FORCEPROP 1 LAST PART_NUMBER G21796-072
J 0
(1365 4525);
DISPLAY 0.617021 (1365 4525);
PAINT BLUE (1365 4525);
FORCEPROP 2 LAST CDS_LIB mstr_discrete
J 0
(1325 4650);
PAINT ORANGE (1325 4650);
DISPLAY INVISIBLE (1325 4650);
FORCEPROP 2 LAST CDS_LOCATION R3P44
J 0
(1370 4775);
DISPLAY 0.617021 (1370 4775);
PAINT AQUA (1370 4775);
DISPLAY INVISIBLE (1370 4775);
FORCEPROP 2 LAST ROOM V_SUPER
J 0
(1375 4825);
DISPLAY 1.021277 (1375 4825);
PAINT ORANGE (1375 4825);
DISPLAY INVISIBLE (1375 4825);
FORCEPROP 1 LAST PATH I59
J 0
(1375 4825);
DISPLAY 0.978723 (1375 4825);
PAINT WHITE (1375 4825);
DISPLAY INVISIBLE (1375 4825);
FORCEPROP 2 LAST SEC_TYPE 0402
J 0
(1375 4875);
DISPLAY 1.021277 (1375 4875);
PAINT ORANGE (1375 4875);
DISPLAY INVISIBLE (1375 4875);
FORCEPROP 2 LAST SEC 1
J 0
(1375 4875);
DISPLAY 0.680851 (1375 4875);
PAINT MONO (1375 4875);
DISPLAY INVISIBLE (1375 4875);
FORCEADD CAP..1
(1225 4050);
FORCEPROP 1 LASTPIN (1225 3950) $PN 2
J 0
(1235 3930);
DISPLAY 0.617021 (1235 3930);
PAINT ORANGE (1235 3930);
FORCEPROP 1 LAST MATERIAL X7R
J 0
(1275 3950);
DISPLAY 0.617021 (1275 3950);
PAINT SKYBLUE (1275 3950);
FORCEPROP 1 LAST PACK_TYPE 0402
J 0
(1275 3850);
DISPLAY 0.617021 (1275 3850);
PAINT SKYBLUE (1275 3850);
FORCEPROP 1 LAST TOLERANCE 10%
J 0
(1275 4000);
DISPLAY 0.617021 (1275 4000);
PAINT SKYBLUE (1275 4000);
FORCEPROP 1 LASTPIN (1225 4150) $PN 1
J 0
(1235 4130);
DISPLAY 0.617021 (1235 4130);
PAINT ORANGE (1235 4130);
FORCEPROP 1 LAST VALUE 0.047UF
J 0
(1275 4100);
DISPLAY 0.617021 (1275 4100);
PAINT SKYBLUE (1275 4100);
FORCEPROP 1 LAST LOCATION C3P45
J 0
(1275 4150);
DISPLAY 0.617021 (1275 4150);
PAINT AQUA (1275 4150);
FORCEPROP 1 LAST PART_NUMBER A36096-090
J 0
(1275 3900);
DISPLAY 0.617021 (1275 3900);
PAINT BLUE (1275 3900);
FORCEPROP 1 LAST VOLTAGE 25V
J 0
(1275 4050);
DISPLAY 0.617021 (1275 4050);
PAINT SKYBLUE (1275 4050);
FORCEPROP 2 LAST CDS_LIB mstr_discrete
J 0
(1225 4050);
PAINT ORANGE (1225 4050);
DISPLAY INVISIBLE (1225 4050);
FORCEPROP 2 LAST ROOM V_SUPER
J 0
(1275 4200);
DISPLAY 1.021277 (1275 4200);
PAINT ORANGE (1275 4200);
DISPLAY INVISIBLE (1275 4200);
FORCEPROP 1 LAST PATH I60
J 0
(1275 4200);
DISPLAY 0.978723 (1275 4200);
PAINT WHITE (1275 4200);
DISPLAY INVISIBLE (1275 4200);
FORCEPROP 2 LAST SEC_TYPE 0402
J 0
(1275 4250);
DISPLAY 1.021277 (1275 4250);
PAINT ORANGE (1275 4250);
DISPLAY INVISIBLE (1275 4250);
FORCEPROP 2 LAST SEC 1
J 0
(1275 4250);
DISPLAY 0.680851 (1275 4250);
PAINT MONO (1275 4250);
DISPLAY INVISIBLE (1275 4250);
FORCEPROP 2 LAST CDS_LOCATION C3P45
J 0
(1275 4150);
DISPLAY 0.617021 (1275 4150);
PAINT AQUA (1275 4150);
DISPLAY INVISIBLE (1275 4150);
FORCEADD GND..1
(1125 4100);
FORCEPROP 3 LASTPIN (1125 4150) SIG_NAME GND\g
J 0
(1135 4160);
DISPLAY 0.659574 (1135 4160);
PAINT MONO (1135 4160);
DISPLAY INVISIBLE (1135 4160);
FORCEPROP 1 LAST VOLTAGE 0.0V
J 0
(1080 4057);
DISPLAY 0.340426 (1080 4057);
PAINT SKYBLUE (1080 4057);
DISPLAY INVISIBLE (1080 4057);
FORCEPROP 1 LAST SIZE 1B
J 0
(1200 4050);
DISPLAY 0.872340 (1200 4050);
PAINT AQUA (1200 4050);
DISPLAY INVISIBLE (1200 4050);
FORCEPROP 2 LAST CDS_LIB mstr_symbols
J 0
(1125 4100);
PAINT ORANGE (1125 4100);
DISPLAY INVISIBLE (1125 4100);
FORCEPROP 1 LAST PATH I61
J 0
(1200 4100);
DISPLAY 0.872340 (1200 4100);
PAINT AQUA (1200 4100);
DISPLAY INVISIBLE (1200 4100);
FORCEPROP 1 LAST BODY_TYPE PLUMBING
J 0
(1080 4057);
DISPLAY 0.340426 (1080 4057);
PAINT GREEN (1080 4057);
DISPLAY INVISIBLE (1080 4057);
FORCEPROP 1 LAST HDL_POWER GND
J 0
(1125 4250);
DISPLAY 0.872340 (1125 4250);
PAINT GREEN (1125 4250);
DISPLAY INVISIBLE (1125 4250);
FORCEADD GND..1
(1225 3850);
FORCEPROP 3 LASTPIN (1225 3900) SIG_NAME GND\g
J 0
(1235 3910);
DISPLAY 0.659574 (1235 3910);
PAINT MONO (1235 3910);
DISPLAY INVISIBLE (1235 3910);
FORCEPROP 1 LAST VOLTAGE 0.0V
J 0
(1180 3807);
DISPLAY 0.340426 (1180 3807);
PAINT SKYBLUE (1180 3807);
DISPLAY INVISIBLE (1180 3807);
FORCEPROP 2 LAST CDS_LIB mstr_symbols
J 0
(1225 3850);
PAINT ORANGE (1225 3850);
DISPLAY INVISIBLE (1225 3850);
FORCEPROP 1 LAST SIZE 1B
J 0
(1300 3800);
DISPLAY 0.872340 (1300 3800);
PAINT AQUA (1300 3800);
DISPLAY INVISIBLE (1300 3800);
FORCEPROP 1 LAST PATH I62
J 0
(1300 3850);
DISPLAY 0.872340 (1300 3850);
PAINT AQUA (1300 3850);
DISPLAY INVISIBLE (1300 3850);
FORCEPROP 1 LAST BODY_TYPE PLUMBING
J 0
(1180 3807);
DISPLAY 0.340426 (1180 3807);
PAINT GREEN (1180 3807);
DISPLAY INVISIBLE (1180 3807);
FORCEPROP 1 LAST HDL_POWER GND
J 0
(1225 4000);
DISPLAY 0.872340 (1225 4000);
PAINT GREEN (1225 4000);
DISPLAY INVISIBLE (1225 4000);
FORCEADD OFFPAGE..2
(1850 2000);
FORCEPROP 2 LASTPIN (1800 2000) SIG_NAME PWRGD_P5V
J 2
(1790 2010);
DISPLAY 0.617021 (1790 2010);
PAINT ORANGE (1790 2010);
FORCEPROP 2 LAST $XR0 190 
J 0
(2039 2000);
DISPLAY 0.638298 (2039 2000);
PAINT MONO (2039 2000);
FORCEPROP 2 LAST CDS_LIB mstr_standard
J 0
(1850 2000);
PAINT ORANGE (1850 2000);
DISPLAY INVISIBLE (1850 2000);
FORCEPROP 2 LAST PATH I63
J 0
(2025 2075);
DISPLAY 1.021277 (2025 2075);
PAINT ORANGE (2025 2075);
DISPLAY INVISIBLE (2025 2075);
FORCEPROP 1 LAST OFFPAGE TRUE
J 0
(2175 1875);
DISPLAY 0.872340 (2175 1875);
PAINT GREEN (2175 1875);
DISPLAY INVISIBLE (2175 1875);
FORCEPROP 1 LAST COMMENT_BODY TRUE
J 0
(1805 1905);
DISPLAY 0.872340 (1805 1905);
PAINT GREEN (1805 1905);
DISPLAY INVISIBLE (1805 1905);
FORCEADD OFFPAGE..2
(1850 1250);
FORCEPROP 2 LASTPIN (1800 1250) SIG_NAME PWRGD_P3V3
J 2
(1790 1260);
DISPLAY 0.617021 (1790 1260);
PAINT ORANGE (1790 1260);
FORCEPROP 2 LAST $XR2 248 
J 0
(2279 1250);
DISPLAY 0.638298 (2279 1250);
PAINT MONO (2279 1250);
FORCEPROP 2 LAST $XR1 190 
J 0
(2159 1250);
DISPLAY 0.638298 (2159 1250);
PAINT MONO (2159 1250);
FORCEPROP 2 LAST $XR0 175 
J 0
(2039 1250);
DISPLAY 0.638298 (2039 1250);
PAINT MONO (2039 1250);
FORCEPROP 2 LAST CDS_LIB mstr_standard
J 0
(1850 1250);
PAINT ORANGE (1850 1250);
DISPLAY INVISIBLE (1850 1250);
FORCEPROP 2 LAST PATH I64
J 0
(2025 1325);
DISPLAY 1.021277 (2025 1325);
PAINT ORANGE (2025 1325);
DISPLAY INVISIBLE (2025 1325);
FORCEPROP 1 LAST OFFPAGE TRUE
J 0
(2175 1125);
DISPLAY 0.872340 (2175 1125);
PAINT GREEN (2175 1125);
DISPLAY INVISIBLE (2175 1125);
FORCEPROP 1 LAST COMMENT_BODY TRUE
J 0
(1805 1155);
DISPLAY 0.872340 (1805 1155);
PAINT GREEN (1805 1155);
DISPLAY INVISIBLE (1805 1155);
FORCEADD RES..1
(1350 2000);
FORCEPROP 1 LASTPIN (1250 2000) $PN 1
J 0
(1262 2012);
DISPLAY 0.617021 (1262 2012);
PAINT ORANGE (1262 2012);
FORCEPROP 1 LAST WATTAGE 1/16W
J 2
(1325 1850);
DISPLAY 0.617021 (1325 1850);
PAINT SKYBLUE (1325 1850);
FORCEPROP 1 LAST VALUE 100.0
J 2
(1325 1900);
DISPLAY 0.617021 (1325 1900);
PAINT SKYBLUE (1325 1900);
FORCEPROP 1 LASTPIN (1450 2000) $PN 2
J 0
(1412 2012);
DISPLAY 0.617021 (1412 2012);
PAINT ORANGE (1412 2012);
FORCEPROP 1 LAST PACK_TYPE 0402
J 0
(1600 1850);
DISPLAY 0.617021 (1600 1850);
PAINT SKYBLUE (1600 1850);
FORCEPROP 1 LAST LOCATION R2P20
J 0
(1300 2050);
DISPLAY 0.617021 (1300 2050);
PAINT AQUA (1300 2050);
FORCEPROP 1 LAST PART_NUMBER G21796-017
J 0
(1300 2100);
DISPLAY 0.617021 (1300 2100);
PAINT BLUE (1300 2100);
FORCEPROP 1 LAST TOLERANCE 1%
J 0
(1350 1900);
DISPLAY 0.617021 (1350 1900);
PAINT SKYBLUE (1350 1900);
FORCEPROP 1 LAST MATERIAL CHIP
J 0
(1350 1850);
DISPLAY 0.617021 (1350 1850);
PAINT SKYBLUE (1350 1850);
FORCEPROP 2 LAST CDS_LIB mstr_discrete
J 0
(1350 2000);
PAINT ORANGE (1350 2000);
DISPLAY INVISIBLE (1350 2000);
FORCEPROP 0 LAST ROOM V_SUPER
J 0
(1300 2200);
DISPLAY 1.021277 (1300 2200);
PAINT ORANGE (1300 2200);
DISPLAY INVISIBLE (1300 2200);
FORCEPROP 1 LAST PATH I65
J 0
(1300 2150);
DISPLAY 0.978723 (1300 2150);
PAINT WHITE (1300 2150);
DISPLAY INVISIBLE (1300 2150);
FORCEPROP 2 LAST SEC_TYPE 0402
J 0
(1300 2200);
DISPLAY 1.021277 (1300 2200);
PAINT ORANGE (1300 2200);
DISPLAY INVISIBLE (1300 2200);
FORCEPROP 2 LAST SEC 1
J 0
(1300 2200);
DISPLAY 0.680851 (1300 2200);
PAINT MONO (1300 2200);
DISPLAY INVISIBLE (1300 2200);
FORCEADD RES..1
(1300 1250);
FORCEPROP 1 LAST WATTAGE 1/16W
J 2
(1275 1100);
DISPLAY 0.617021 (1275 1100);
PAINT SKYBLUE (1275 1100);
FORCEPROP 1 LAST VALUE 49.9
J 2
(1275 1150);
DISPLAY 0.617021 (1275 1150);
PAINT SKYBLUE (1275 1150);
FORCEPROP 1 LASTPIN (1200 1250) $PN 1
J 0
(1212 1262);
DISPLAY 0.617021 (1212 1262);
PAINT ORANGE (1212 1262);
FORCEPROP 1 LAST LOCATION R1L16
J 0
(1250 1300);
DISPLAY 0.617021 (1250 1300);
PAINT AQUA (1250 1300);
FORCEPROP 1 LASTPIN (1400 1250) $PN 2
J 0
(1362 1262);
DISPLAY 0.617021 (1362 1262);
PAINT ORANGE (1362 1262);
FORCEPROP 1 LAST MATERIAL CHIP
J 0
(1300 1100);
DISPLAY 0.617021 (1300 1100);
PAINT SKYBLUE (1300 1100);
FORCEPROP 1 LAST TOLERANCE 1%
J 0
(1300 1150);
DISPLAY 0.617021 (1300 1150);
PAINT SKYBLUE (1300 1150);
FORCEPROP 1 LAST PACK_TYPE 0402
J 0
(1550 1100);
DISPLAY 0.617021 (1550 1100);
PAINT SKYBLUE (1550 1100);
FORCEPROP 1 LAST PART_NUMBER G21796-047
J 0
(1250 1350);
DISPLAY 0.617021 (1250 1350);
PAINT BLUE (1250 1350);
FORCEPROP 1 LAST PATH I68
J 0
(1250 1400);
DISPLAY 0.978723 (1250 1400);
PAINT WHITE (1250 1400);
DISPLAY INVISIBLE (1250 1400);
FORCEPROP 0 LAST ROOM V_SUPER
J 0
(1250 1450);
DISPLAY 1.021277 (1250 1450);
PAINT ORANGE (1250 1450);
DISPLAY INVISIBLE (1250 1450);
FORCEPROP 2 LAST CDS_LOCATION R1L16
J 0
(1250 1300);
DISPLAY 0.617021 (1250 1300);
PAINT AQUA (1250 1300);
DISPLAY INVISIBLE (1250 1300);
FORCEPROP 2 LAST SEC 1
J 0
(1250 1450);
DISPLAY 0.680851 (1250 1450);
PAINT MONO (1250 1450);
DISPLAY INVISIBLE (1250 1450);
FORCEPROP 2 LAST SEC_TYPE 0402
J 0
(1250 1450);
DISPLAY 1.021277 (1250 1450);
PAINT ORANGE (1250 1450);
DISPLAY INVISIBLE (1250 1450);
FORCEPROP 2 LAST CDS_LIB mstr_discrete
J 0
(1300 1250);
PAINT ORANGE (1300 1250);
DISPLAY INVISIBLE (1300 1250);
FORCEADD P3V3_STBY..1
(275 4900);
FORCEPROP 3 LASTPIN (275 4850) SIG_NAME P3V3_STBY\g
J 0
(285 4860);
DISPLAY 0.659574 (285 4860);
PAINT MONO (285 4860);
DISPLAY INVISIBLE (285 4860);
FORCEPROP 1 LAST VOLTAGE 3.3V
J 0
(230 4857);
DISPLAY 0.340426 (230 4857);
PAINT SKYBLUE (230 4857);
DISPLAY INVISIBLE (230 4857);
FORCEPROP 1 LAST PATH I69
J 0
(320 4902);
DISPLAY 0.340426 (320 4902);
PAINT GREEN (320 4902);
DISPLAY INVISIBLE (320 4902);
FORCEPROP 2 LAST CDS_LIB mstr_symbols
J 0
(275 4900);
PAINT ORANGE (275 4900);
DISPLAY INVISIBLE (275 4900);
FORCEPROP 1 LAST SIZE 1B
J 0
(320 4922);
DISPLAY 0.340426 (320 4922);
PAINT GREEN (320 4922);
DISPLAY INVISIBLE (320 4922);
FORCEPROP 1 LAST BODY_TYPE PLUMBING
J 0
(230 4857);
DISPLAY 0.340426 (230 4857);
PAINT GREEN (230 4857);
DISPLAY INVISIBLE (230 4857);
FORCEPROP 1 LAST HDL_POWER P3V3_STBY
J 0
(-25 4775);
DISPLAY 0.872340 (-25 4775);
PAINT ORANGE (-25 4775);
DISPLAY INVISIBLE (-25 4775);
FORCEADD ADM1085..1
(725 4400);
FORCEPROP 2 LASTPIN (375 4450) $PN 3
J 2
(365 4460);
DISPLAY 0.617021 (365 4460);
PAINT ORANGE (365 4460);
FORCEPROP 2 LASTPIN (375 4500) $PN 6
J 2
(365 4510);
DISPLAY 0.617021 (365 4510);
PAINT ORANGE (365 4510);
FORCEPROP 1 LAST MATERIAL IC
J 0
(425 4700);
DISPLAY 0.617021 (425 4700);
PAINT SKYBLUE (425 4700);
FORCEPROP 1 LAST LOCATION U7D3
J 0
(425 4750);
DISPLAY 0.617021 (425 4750);
PAINT AQUA (425 4750);
FORCEPROP 2 LASTPIN (1075 4200) $PN 2
J 0
(1085 4210);
DISPLAY 0.617021 (1085 4210);
PAINT ORANGE (1085 4210);
FORCEPROP 2 LASTPIN (1075 4250) $PN 5
J 0
(1085 4260);
DISPLAY 0.617021 (1085 4260);
PAINT ORANGE (1085 4260);
FORCEPROP 2 LASTPIN (1075 4350) $PN 4
J 0
(1085 4360);
DISPLAY 0.617021 (1085 4360);
PAINT ORANGE (1085 4360);
FORCEPROP 2 LASTPIN (375 4350) $PN 1
J 2
(365 4360);
DISPLAY 0.617021 (365 4360);
PAINT ORANGE (365 4360);
FORCEPROP 1 LAST PART_NUMBER H46130-001
J 0
(425 4100);
DISPLAY 0.617021 (425 4100);
PAINT BLUE (425 4100);
FORCEPROP 2 LAST ROOM V_SUPER
J 0
(425 4800);
DISPLAY 1.021277 (425 4800);
PAINT ORANGE (425 4800);
DISPLAY INVISIBLE (425 4800);
FORCEPROP 2 LAST CDS_LOCATION U7D3
J 0
(425 4750);
DISPLAY 0.617021 (425 4750);
PAINT AQUA (425 4750);
DISPLAY INVISIBLE (425 4750);
FORCEPROP 2 LAST SEC 1
J 0
(425 4800);
DISPLAY 0.680851 (425 4800);
PAINT MONO (425 4800);
DISPLAY INVISIBLE (425 4800);
FORCEPROP 2 LAST SEC_TYPE SMT
J 0
(425 4800);
DISPLAY 1.021277 (425 4800);
PAINT ORANGE (425 4800);
DISPLAY INVISIBLE (425 4800);
FORCEPROP 1 LAST PACK_TYPE SMT
J 0
(425 4800);
PAINT SKYBLUE (425 4800);
DISPLAY INVISIBLE (425 4800);
FORCEPROP 1 LAST PATH I70
J 0
(725 4700);
PAINT GREEN (725 4700);
DISPLAY INVISIBLE (725 4700);
FORCEPROP 2 LAST CDS_LIB mstr_analog
J 0
(725 4400);
PAINT ORANGE (725 4400);
DISPLAY INVISIBLE (725 4400);
FORCEADD RES..2
(-25 4750);
FORCEPROP 1 LASTPIN (-25 4650) $PN 2
J 0
(-20 4660);
DISPLAY 0.617021 (-20 4660);
PAINT ORANGE (-20 4660);
FORCEPROP 1 LASTPIN (-25 4850) $PN 1
J 0
(-20 4812);
DISPLAY 0.617021 (-20 4812);
PAINT ORANGE (-20 4812);
FORCEPROP 1 LAST PACK_TYPE 0402
J 0
(15 4575);
DISPLAY 0.617021 (15 4575);
PAINT SKYBLUE (15 4575);
FORCEPROP 1 LAST TOLERANCE 1%
J 0
(20 4775);
DISPLAY 0.617021 (20 4775);
PAINT SKYBLUE (20 4775);
FORCEPROP 1 LAST WATTAGE 1/16W
J 0
(15 4725);
DISPLAY 0.617021 (15 4725);
PAINT SKYBLUE (15 4725);
FORCEPROP 1 LAST VALUE 10.0K
J 0
(20 4825);
DISPLAY 0.617021 (20 4825);
PAINT SKYBLUE (20 4825);
FORCEPROP 1 LAST MATERIAL EMPTY
J 0
(15 4675);
DISPLAY 0.617021 (15 4675);
PAINT RED (15 4675);
FORCEPROP 1 LAST LOCATION R3P50
J 0
(20 4875);
DISPLAY 0.617021 (20 4875);
PAINT AQUA (20 4875);
FORCEPROP 1 LAST PART_NUMBER G21796-016
J 0
(15 4625);
DISPLAY 0.617021 (15 4625);
PAINT BLUE (15 4625);
FORCEPROP 2 LAST CDS_LIB mstr_discrete
J 0
(-25 4750);
PAINT ORANGE (-25 4750);
DISPLAY INVISIBLE (-25 4750);
FORCEPROP 2 LAST ROOM V_SUPER
J 0
(25 4925);
DISPLAY 1.021277 (25 4925);
PAINT ORANGE (25 4925);
DISPLAY INVISIBLE (25 4925);
FORCEPROP 1 LAST PATH I71
J 0
(25 4925);
DISPLAY 0.978723 (25 4925);
PAINT WHITE (25 4925);
DISPLAY INVISIBLE (25 4925);
FORCEPROP 2 LAST SEC_TYPE 0402
J 0
(25 4975);
DISPLAY 1.021277 (25 4975);
PAINT ORANGE (25 4975);
DISPLAY INVISIBLE (25 4975);
FORCEPROP 2 LAST SEC 1
J 0
(25 4975);
DISPLAY 0.680851 (25 4975);
PAINT MONO (25 4975);
DISPLAY INVISIBLE (25 4975);
FORCEPROP 2 LAST CDS_LOCATION R3P50
J 0
(20 4875);
DISPLAY 0.617021 (20 4875);
PAINT AQUA (20 4875);
DISPLAY INVISIBLE (20 4875);
FORCEADD CAP_A..1
(275 3950);
FORCEPROP 1 LAST PACK_TYPE 0402V
J 0
(325 3750);
DISPLAY 0.617021 (325 3750);
PAINT SKYBLUE (325 3750);
FORCEPROP 1 LASTPIN (275 3850) $PN 2
J 0
(285 3830);
DISPLAY 0.617021 (285 3830);
PAINT ORANGE (285 3830);
FORCEPROP 1 LASTPIN (275 4050) $PN 1
J 0
(285 4030);
DISPLAY 0.617021 (285 4030);
PAINT ORANGE (285 4030);
FORCEPROP 1 LAST MATERIAL X7R
J 0
(325 3850);
DISPLAY 0.617021 (325 3850);
PAINT SKYBLUE (325 3850);
FORCEPROP 1 LAST VOLTAGE 16V
J 0
(325 3950);
DISPLAY 0.617021 (325 3950);
PAINT SKYBLUE (325 3950);
FORCEPROP 1 LAST TOLERANCE 10%
J 0
(325 3900);
DISPLAY 0.617021 (325 3900);
PAINT SKYBLUE (325 3900);
FORCEPROP 1 LAST VALUE 0.1UF
J 0
(325 4000);
DISPLAY 0.617021 (325 4000);
PAINT SKYBLUE (325 4000);
FORCEPROP 1 LAST LOCATION C3P46
J 0
(325 4050);
DISPLAY 0.617021 (325 4050);
PAINT AQUA (325 4050);
FORCEPROP 1 LAST PART_NUMBER A36096-030
J 0
(325 3800);
DISPLAY 0.617021 (325 3800);
PAINT BLUE (325 3800);
FORCEPROP 2 LAST CDS_LIB dev_discrete
J 0
(275 3950);
PAINT ORANGE (275 3950);
DISPLAY INVISIBLE (275 3950);
FORCEPROP 2 LAST CDS_LOCATION C3P46
J 0
(325 4050);
DISPLAY 0.617021 (325 4050);
PAINT AQUA (325 4050);
DISPLAY INVISIBLE (325 4050);
FORCEPROP 2 LAST ROOM V_SUPER
J 0
(325 4100);
DISPLAY 1.021277 (325 4100);
PAINT ORANGE (325 4100);
DISPLAY INVISIBLE (325 4100);
FORCEPROP 1 LAST PATH I72
J 0
(325 4100);
DISPLAY 0.978723 (325 4100);
PAINT WHITE (325 4100);
DISPLAY INVISIBLE (325 4100);
FORCEPROP 2 LAST SEC_TYPE 0402V
J 0
(325 4150);
DISPLAY 1.021277 (325 4150);
PAINT ORANGE (325 4150);
DISPLAY INVISIBLE (325 4150);
FORCEPROP 2 LAST SEC 1
J 0
(325 4150);
DISPLAY 0.680851 (325 4150);
PAINT MONO (325 4150);
DISPLAY INVISIBLE (325 4150);
FORCEADD GND..1
(275 3750);
FORCEPROP 3 LASTPIN (275 3800) SIG_NAME GND\g
J 0
(285 3810);
DISPLAY 0.659574 (285 3810);
PAINT MONO (285 3810);
DISPLAY INVISIBLE (285 3810);
FORCEPROP 1 LAST VOLTAGE 0.0V
J 0
(230 3707);
DISPLAY 0.340426 (230 3707);
PAINT SKYBLUE (230 3707);
DISPLAY INVISIBLE (230 3707);
FORCEPROP 2 LAST CDS_LIB mstr_symbols
J 0
(275 3750);
PAINT ORANGE (275 3750);
DISPLAY INVISIBLE (275 3750);
FORCEPROP 1 LAST SIZE 1B
J 0
(350 3700);
DISPLAY 0.872340 (350 3700);
PAINT AQUA (350 3700);
DISPLAY INVISIBLE (350 3700);
FORCEPROP 1 LAST PATH I73
J 0
(350 3750);
DISPLAY 0.872340 (350 3750);
PAINT AQUA (350 3750);
DISPLAY INVISIBLE (350 3750);
FORCEPROP 1 LAST BODY_TYPE PLUMBING
J 0
(230 3707);
DISPLAY 0.340426 (230 3707);
PAINT GREEN (230 3707);
DISPLAY INVISIBLE (230 3707);
FORCEPROP 1 LAST HDL_POWER GND
J 0
(275 3900);
DISPLAY 0.872340 (275 3900);
PAINT GREEN (275 3900);
DISPLAY INVISIBLE (275 3900);
FORCEADD RES..2
(-525 4750);
FORCEPROP 1 LASTPIN (-525 4650) $PN 2
J 0
(-520 4660);
DISPLAY 0.617021 (-520 4660);
PAINT ORANGE (-520 4660);
FORCEPROP 1 LASTPIN (-525 4850) $PN 1
J 0
(-520 4812);
DISPLAY 0.617021 (-520 4812);
PAINT ORANGE (-520 4812);
FORCEPROP 1 LAST PACK_TYPE 0402
J 0
(-485 4575);
DISPLAY 0.617021 (-485 4575);
PAINT SKYBLUE (-485 4575);
FORCEPROP 1 LAST WATTAGE 1/16W
J 0
(-485 4725);
DISPLAY 0.617021 (-485 4725);
PAINT SKYBLUE (-485 4725);
FORCEPROP 1 LAST MATERIAL CHIP
J 0
(-485 4675);
DISPLAY 0.617021 (-485 4675);
PAINT SKYBLUE (-485 4675);
FORCEPROP 1 LAST TOLERANCE 1%
J 0
(-480 4775);
DISPLAY 0.617021 (-480 4775);
PAINT SKYBLUE (-480 4775);
FORCEPROP 1 LAST VALUE 90.9K
J 0
(-480 4825);
DISPLAY 0.617021 (-480 4825);
PAINT SKYBLUE (-480 4825);
FORCEPROP 1 LAST LOCATION R3P48
J 0
(-480 4875);
DISPLAY 0.617021 (-480 4875);
PAINT AQUA (-480 4875);
FORCEPROP 1 LAST PART_NUMBER G21796-058
J 0
(-485 4625);
DISPLAY 0.617021 (-485 4625);
PAINT BLUE (-485 4625);
FORCEPROP 2 LAST CDS_LIB mstr_discrete
J 0
(-525 4750);
PAINT ORANGE (-525 4750);
DISPLAY INVISIBLE (-525 4750);
FORCEPROP 2 LAST ROOM V_SUPER
J 0
(-475 4925);
DISPLAY 1.021277 (-475 4925);
PAINT ORANGE (-475 4925);
DISPLAY INVISIBLE (-475 4925);
FORCEPROP 1 LAST PATH I74
J 0
(-475 4925);
DISPLAY 0.978723 (-475 4925);
PAINT WHITE (-475 4925);
DISPLAY INVISIBLE (-475 4925);
FORCEPROP 2 LAST SEC_TYPE 0402
J 0
(-475 4975);
DISPLAY 1.021277 (-475 4975);
PAINT ORANGE (-475 4975);
DISPLAY INVISIBLE (-475 4975);
FORCEPROP 2 LAST SEC 1
J 0
(-475 4975);
DISPLAY 0.680851 (-475 4975);
PAINT MONO (-475 4975);
DISPLAY INVISIBLE (-475 4975);
FORCEPROP 2 LAST CDS_LOCATION R3P48
J 0
(-480 4875);
DISPLAY 0.617021 (-480 4875);
PAINT AQUA (-480 4875);
DISPLAY INVISIBLE (-480 4875);
FORCEADD RES..2
(-525 4250);
FORCEPROP 1 LASTPIN (-525 4150) $PN 2
J 0
(-520 4160);
DISPLAY 0.617021 (-520 4160);
PAINT ORANGE (-520 4160);
FORCEPROP 1 LASTPIN (-525 4350) $PN 1
J 0
(-520 4312);
DISPLAY 0.617021 (-520 4312);
PAINT ORANGE (-520 4312);
FORCEPROP 1 LAST LOCATION R3P51
J 0
(-480 4375);
DISPLAY 0.617021 (-480 4375);
PAINT AQUA (-480 4375);
FORCEPROP 1 LAST VALUE 6.34K
J 0
(-480 4325);
DISPLAY 0.617021 (-480 4325);
PAINT SKYBLUE (-480 4325);
FORCEPROP 1 LAST TOLERANCE 1%
J 0
(-480 4275);
DISPLAY 0.617021 (-480 4275);
PAINT SKYBLUE (-480 4275);
FORCEPROP 1 LAST WATTAGE 1/16W
J 0
(-485 4225);
DISPLAY 0.617021 (-485 4225);
PAINT SKYBLUE (-485 4225);
FORCEPROP 1 LAST PART_NUMBER G21796-146
J 0
(-485 4125);
DISPLAY 0.617021 (-485 4125);
PAINT BLUE (-485 4125);
FORCEPROP 1 LAST PACK_TYPE 0402
J 0
(-485 4075);
DISPLAY 0.617021 (-485 4075);
PAINT SKYBLUE (-485 4075);
FORCEPROP 1 LAST MATERIAL CHIP
J 0
(-485 4175);
DISPLAY 0.617021 (-485 4175);
PAINT SKYBLUE (-485 4175);
FORCEPROP 2 LAST CDS_LIB mstr_discrete
J 0
(-525 4250);
PAINT MONO (-525 4250);
DISPLAY INVISIBLE (-525 4250);
FORCEPROP 2 LAST CDS_LOCATION R3P51
J 0
(-480 4375);
DISPLAY 0.617021 (-480 4375);
PAINT AQUA (-480 4375);
DISPLAY INVISIBLE (-480 4375);
FORCEPROP 2 LAST SEC 1
J 0
(-475 4475);
PAINT MONO (-475 4475);
DISPLAY INVISIBLE (-475 4475);
FORCEPROP 2 LAST SEC_TYPE 0402
J 0
(-475 4475);
DISPLAY 1.021277 (-475 4475);
PAINT ORANGE (-475 4475);
DISPLAY INVISIBLE (-475 4475);
FORCEPROP 1 LAST PATH I75
J 0
(-475 4425);
DISPLAY 0.978723 (-475 4425);
PAINT WHITE (-475 4425);
DISPLAY INVISIBLE (-475 4425);
FORCEPROP 2 LAST ROOM V_SUPER
J 0
(-475 4425);
DISPLAY 1.021277 (-475 4425);
PAINT ORANGE (-475 4425);
DISPLAY INVISIBLE (-475 4425);
FORCEADD GND..1
(-525 4050);
FORCEPROP 3 LASTPIN (-525 4100) SIG_NAME GND\g
J 0
(-515 4110);
DISPLAY 0.659574 (-515 4110);
PAINT MONO (-515 4110);
DISPLAY INVISIBLE (-515 4110);
FORCEPROP 2 LAST CDS_LIB mstr_symbols
J 0
(-525 4050);
PAINT ORANGE (-525 4050);
DISPLAY INVISIBLE (-525 4050);
FORCEPROP 1 LAST VOLTAGE 0.0V
J 0
(-570 4007);
DISPLAY 0.340426 (-570 4007);
PAINT SKYBLUE (-570 4007);
DISPLAY INVISIBLE (-570 4007);
FORCEPROP 1 LAST SIZE 1B
J 0
(-450 4000);
DISPLAY 0.872340 (-450 4000);
PAINT AQUA (-450 4000);
DISPLAY INVISIBLE (-450 4000);
FORCEPROP 1 LAST PATH I76
J 0
(-450 4050);
DISPLAY 0.872340 (-450 4050);
PAINT AQUA (-450 4050);
DISPLAY INVISIBLE (-450 4050);
FORCEPROP 1 LAST BODY_TYPE PLUMBING
J 0
(-570 4007);
DISPLAY 0.340426 (-570 4007);
PAINT GREEN (-570 4007);
DISPLAY INVISIBLE (-570 4007);
FORCEPROP 1 LAST HDL_POWER GND
J 0
(-525 4200);
DISPLAY 0.872340 (-525 4200);
PAINT GREEN (-525 4200);
DISPLAY INVISIBLE (-525 4200);
FORCEADD ADM809..1
(200 1350);
FORCEPROP 2 LASTPIN (0 1400) $PN 3
J 2
(-10 1410);
DISPLAY 0.617021 (-10 1410);
PAINT ORANGE (-10 1410);
FORCEPROP 1 LAST POWER_GROUP GND=GND;
J 0
(50 1000);
DISPLAY 0.617021 (50 1000);
PAINT ORANGE (50 1000);
FORCEPROP 2 LASTPIN (400 1250) $PN 2
J 0
(410 1260);
DISPLAY 0.617021 (410 1260);
PAINT ORANGE (410 1260);
FORCEPROP 1 LAST PART_NUMBER D23047-001
J 0
(55 1055);
DISPLAY 0.617021 (55 1055);
PAINT BLUE (55 1055);
FORCEPROP 1 LAST MATERIAL IC
J 0
(55 1568);
DISPLAY 0.617021 (55 1568);
PAINT SKYBLUE (55 1568);
FORCEPROP 1 LAST LOCATION U1L3
J 0
(55 1609);
DISPLAY 0.617021 (55 1609);
PAINT AQUA (55 1609);
FORCEPROP 2 LAST CDS_LIB mstr_analog
J 0
(200 1350);
PAINT ORANGE (200 1350);
DISPLAY INVISIBLE (200 1350);
FORCEPROP 2 LAST CDS_LOCATION U1L3
J 0
(55 1609);
DISPLAY 0.617021 (55 1609);
PAINT AQUA (55 1609);
DISPLAY INVISIBLE (55 1609);
FORCEPROP 2 LAST $SEC 1
J 0
(75 1650);
DISPLAY 0.680851 (75 1650);
PAINT MONO (75 1650);
DISPLAY INVISIBLE (75 1650);
FORCEPROP 1 LAST PACK_TYPE SMLF
J 0
(55 1650);
DISPLAY 0.872340 (55 1650);
PAINT SKYBLUE (55 1650);
DISPLAY INVISIBLE (55 1650);
FORCEPROP 2 LAST CDS_SEC 1
J 0
(75 1650);
DISPLAY 1.021277 (75 1650);
PAINT ORANGE (75 1650);
DISPLAY INVISIBLE (75 1650);
FORCEPROP 2 LAST ROOM V_SUPER
J 0
(75 1650);
DISPLAY 1.021277 (75 1650);
PAINT ORANGE (75 1650);
DISPLAY INVISIBLE (75 1650);
FORCEPROP 1 LAST PATH I80
J 0
(455 1560);
DISPLAY 0.872340 (455 1560);
PAINT PURPLE (455 1560);
DISPLAY INVISIBLE (455 1560);
FORCEADD CAP_A..1
(-300 1250);
FORCEPROP 1 LAST MATERIAL X7R
J 0
(-250 1150);
DISPLAY 0.617021 (-250 1150);
PAINT SKYBLUE (-250 1150);
FORCEPROP 1 LAST VOLTAGE 16V
J 0
(-250 1250);
DISPLAY 0.617021 (-250 1250);
PAINT SKYBLUE (-250 1250);
FORCEPROP 1 LAST TOLERANCE 10%
J 0
(-250 1200);
DISPLAY 0.617021 (-250 1200);
PAINT SKYBLUE (-250 1200);
FORCEPROP 1 LAST VALUE 0.1UF
J 0
(-250 1300);
DISPLAY 0.617021 (-250 1300);
PAINT SKYBLUE (-250 1300);
FORCEPROP 1 LAST LOCATION C1L16
J 0
(-250 1350);
DISPLAY 0.617021 (-250 1350);
PAINT AQUA (-250 1350);
FORCEPROP 1 LAST PART_NUMBER A36096-030
J 0
(-250 1100);
DISPLAY 0.617021 (-250 1100);
PAINT BLUE (-250 1100);
FORCEPROP 1 LAST PACK_TYPE 0402V
J 0
(-250 1050);
DISPLAY 0.617021 (-250 1050);
PAINT SKYBLUE (-250 1050);
FORCEPROP 1 LASTPIN (-300 1150) $PN 2
J 0
(-290 1130);
DISPLAY 0.787234 (-290 1130);
PAINT ORANGE (-290 1130);
FORCEPROP 1 LASTPIN (-300 1350) $PN 1
J 0
(-290 1330);
DISPLAY 0.787234 (-290 1330);
PAINT ORANGE (-290 1330);
FORCEPROP 2 LAST CDS_LIB dev_discrete
J 0
(-300 1250);
PAINT ORANGE (-300 1250);
DISPLAY INVISIBLE (-300 1250);
FORCEPROP 2 LAST ROOM V_SUPER
J 0
(-250 1400);
DISPLAY 1.021277 (-250 1400);
PAINT ORANGE (-250 1400);
DISPLAY INVISIBLE (-250 1400);
FORCEPROP 1 LAST PATH I81
J 0
(-250 1400);
DISPLAY 0.978723 (-250 1400);
PAINT WHITE (-250 1400);
DISPLAY INVISIBLE (-250 1400);
FORCEPROP 2 LAST CDS_LOCATION C1L16
J 0
(-250 1350);
DISPLAY 0.617021 (-250 1350);
PAINT AQUA (-250 1350);
DISPLAY INVISIBLE (-250 1350);
FORCEPROP 0 LAST SEC 1
J 0
(-250 1400);
DISPLAY 0.680851 (-250 1400);
PAINT MONO (-250 1400);
DISPLAY INVISIBLE (-250 1400);
FORCEPROP 2 LAST SEC_TYPE 0402V
J 0
(-250 1450);
DISPLAY 1.021277 (-250 1450);
PAINT ORANGE (-250 1450);
DISPLAY INVISIBLE (-250 1450);
FORCEADD GND..1
(-300 1050);
FORCEPROP 3 LASTPIN (-300 1100) SIG_NAME GND\g
J 0
(-290 1110);
DISPLAY 0.659574 (-290 1110);
PAINT MONO (-290 1110);
DISPLAY INVISIBLE (-290 1110);
FORCEPROP 1 LAST VOLTAGE 0.0V
J 0
(-345 1007);
DISPLAY 0.340426 (-345 1007);
PAINT SKYBLUE (-345 1007);
DISPLAY INVISIBLE (-345 1007);
FORCEPROP 1 LAST SIZE 1B
J 0
(-225 1000);
DISPLAY 0.872340 (-225 1000);
PAINT AQUA (-225 1000);
DISPLAY INVISIBLE (-225 1000);
FORCEPROP 2 LAST CDS_LIB mstr_symbols
J 0
(-300 1050);
PAINT ORANGE (-300 1050);
DISPLAY INVISIBLE (-300 1050);
FORCEPROP 1 LAST PATH I82
J 0
(-225 1050);
DISPLAY 0.872340 (-225 1050);
PAINT AQUA (-225 1050);
DISPLAY INVISIBLE (-225 1050);
FORCEPROP 1 LAST BODY_TYPE PLUMBING
J 0
(-345 1007);
DISPLAY 0.340426 (-345 1007);
PAINT GREEN (-345 1007);
DISPLAY INVISIBLE (-345 1007);
FORCEPROP 1 LAST HDL_POWER GND
J 0
(-300 1200);
DISPLAY 0.872340 (-300 1200);
PAINT GREEN (-300 1200);
DISPLAY INVISIBLE (-300 1200);
FORCEADD P3V3..1
(-300 1500);
FORCEPROP 3 LASTPIN (-300 1450) SIG_NAME P3V3\g
J 0
(-290 1460);
DISPLAY 0.659574 (-290 1460);
PAINT MONO (-290 1460);
DISPLAY INVISIBLE (-290 1460);
FORCEPROP 1 LAST VOLTAGE 3.3V
J 0
(-345 1457);
DISPLAY 0.340426 (-345 1457);
PAINT SKYBLUE (-345 1457);
DISPLAY INVISIBLE (-345 1457);
FORCEPROP 1 LAST PATH I83
J 0
(-255 1502);
DISPLAY 0.340426 (-255 1502);
PAINT GREEN (-255 1502);
DISPLAY INVISIBLE (-255 1502);
FORCEPROP 2 LAST CDS_LIB mstr_symbols
J 0
(-300 1500);
PAINT ORANGE (-300 1500);
DISPLAY INVISIBLE (-300 1500);
FORCEPROP 1 LAST SIZE 1B
J 0
(-255 1522);
DISPLAY 0.340426 (-255 1522);
PAINT GREEN (-255 1522);
DISPLAY INVISIBLE (-255 1522);
FORCEPROP 1 LAST BODY_TYPE PLUMBING
J 0
(-345 1457);
DISPLAY 0.340426 (-345 1457);
PAINT GREEN (-345 1457);
DISPLAY INVISIBLE (-345 1457);
FORCEPROP 1 LAST HDL_POWER P3V3
J 0
(-625 1375);
DISPLAY 0.872340 (-625 1375);
PAINT ORANGE (-625 1375);
DISPLAY INVISIBLE (-625 1375);
FORCEADD OFFPAGE..2
(2025 4350);
FORCEPROP 2 LASTPIN (1975 4350) SIG_NAME PWRGD_DSW_PWROK
J 2
(1965 4360);
DISPLAY 0.617021 (1965 4360);
PAINT ORANGE (1965 4360);
FORCEPROP 2 LAST $XR4 247 
J 0
(2334 4314);
DISPLAY 0.638298 (2334 4314);
PAINT MONO (2334 4314);
FORCEPROP 2 LAST $XR3 191 
J 0
(2214 4314);
DISPLAY 0.638298 (2214 4314);
PAINT MONO (2214 4314);
FORCEPROP 2 LAST $XR2 157 
J 0
(2454 4350);
DISPLAY 0.638298 (2454 4350);
PAINT MONO (2454 4350);
FORCEPROP 2 LAST $XR1 118 
J 0
(2334 4350);
DISPLAY 0.638298 (2334 4350);
PAINT MONO (2334 4350);
FORCEPROP 2 LAST $XR0 200 
J 0
(2214 4350);
DISPLAY 0.638298 (2214 4350);
PAINT MONO (2214 4350);
FORCEPROP 2 LAST CDS_LIB mstr_standard
J 0
(2025 4350);
PAINT ORANGE (2025 4350);
DISPLAY INVISIBLE (2025 4350);
FORCEPROP 2 LAST PATH I88
J 0
(2200 4425);
DISPLAY 1.021277 (2200 4425);
PAINT ORANGE (2200 4425);
DISPLAY INVISIBLE (2200 4425);
FORCEPROP 1 LAST OFFPAGE TRUE
J 0
(2350 4225);
DISPLAY 0.872340 (2350 4225);
PAINT GREEN (2350 4225);
DISPLAY INVISIBLE (2350 4225);
FORCEPROP 1 LAST COMMENT_BODY TRUE
J 0
(1980 4255);
DISPLAY 0.872340 (1980 4255);
PAINT GREEN (1980 4255);
DISPLAY INVISIBLE (1980 4255);
FORCEADD ADM809..1
(400 3100);
FORCEPROP 1 LAST POWER_GROUP GND=GND;
J 0
(250 2750);
DISPLAY 0.617021 (250 2750);
PAINT ORANGE (250 2750);
FORCEPROP 1 LAST PART_NUMBER D23047-001
J 0
(255 2805);
DISPLAY 0.617021 (255 2805);
PAINT BLUE (255 2805);
FORCEPROP 2 LASTPIN (600 3000) $PN 2
J 0
(610 3010);
DISPLAY 0.617021 (610 3010);
PAINT MONO (610 3010);
FORCEPROP 2 LASTPIN (200 3150) $PN 3
J 2
(190 3160);
DISPLAY 0.617021 (190 3160);
PAINT MONO (190 3160);
FORCEPROP 1 LAST MATERIAL IC
J 0
(255 3318);
DISPLAY 0.617021 (255 3318);
PAINT SKYBLUE (255 3318);
FORCEPROP 1 LAST LOCATION U8E2
J 0
(255 3359);
DISPLAY 0.617021 (255 3359);
PAINT AQUA (255 3359);
FORCEPROP 2 LAST ROOM V_SUPER
J 0
(275 3400);
DISPLAY 1.021277 (275 3400);
PAINT ORANGE (275 3400);
DISPLAY INVISIBLE (275 3400);
FORCEPROP 2 LAST CDS_LOCATION U8E2
J 0
(255 3359);
DISPLAY 0.617021 (255 3359);
PAINT AQUA (255 3359);
DISPLAY INVISIBLE (255 3359);
FORCEPROP 2 LAST $SEC 1
J 0
(275 3400);
PAINT MONO (275 3400);
DISPLAY INVISIBLE (275 3400);
FORCEPROP 2 LAST CDS_SEC 1
J 0
(275 3400);
PAINT MONO (275 3400);
DISPLAY INVISIBLE (275 3400);
FORCEPROP 2 LAST CDS_LIB mstr_analog
J 0
(400 3100);
PAINT MONO (400 3100);
DISPLAY INVISIBLE (400 3100);
FORCEPROP 1 LAST PACK_TYPE SMLF
J 0
(255 3400);
DISPLAY 0.872340 (255 3400);
PAINT SKYBLUE (255 3400);
DISPLAY INVISIBLE (255 3400);
FORCEPROP 1 LAST PATH I89
J 0
(655 3310);
DISPLAY 0.872340 (655 3310);
PAINT PURPLE (655 3310);
DISPLAY INVISIBLE (655 3310);
FORCEADD RES..1
(1325 3000);
FORCEPROP 1 LAST PART_NUMBER G21796-250
J 0
(1275 3100);
DISPLAY 0.617021 (1275 3100);
PAINT BLUE (1275 3100);
FORCEPROP 1 LASTPIN (1425 3000) $PN 2
J 0
(1387 3012);
DISPLAY 0.617021 (1387 3012);
PAINT ORANGE (1387 3012);
FORCEPROP 1 LAST TOLERANCE 1.0%
J 0
(1325 2900);
DISPLAY 0.617021 (1325 2900);
PAINT SKYBLUE (1325 2900);
FORCEPROP 1 LAST MATERIAL CHIP
J 0
(1325 2850);
DISPLAY 0.617021 (1325 2850);
PAINT SKYBLUE (1325 2850);
FORCEPROP 1 LAST VALUE 22.1
J 2
(1300 2900);
DISPLAY 0.617021 (1300 2900);
PAINT SKYBLUE (1300 2900);
FORCEPROP 1 LAST LOCATION R8E7
J 0
(1275 3050);
DISPLAY 0.617021 (1275 3050);
PAINT AQUA (1275 3050);
FORCEPROP 1 LASTPIN (1225 3000) $PN 1
J 0
(1237 3012);
DISPLAY 0.617021 (1237 3012);
PAINT ORANGE (1237 3012);
FORCEPROP 1 LAST WATTAGE 1/16W
J 2
(1300 2850);
DISPLAY 0.617021 (1300 2850);
PAINT SKYBLUE (1300 2850);
FORCEPROP 1 LAST PACK_TYPE 0402
J 0
(1575 2850);
DISPLAY 0.617021 (1575 2850);
PAINT SKYBLUE (1575 2850);
FORCEPROP 0 LAST ROOM V_SUPER
J 0
(1275 3200);
DISPLAY 1.021277 (1275 3200);
PAINT ORANGE (1275 3200);
DISPLAY INVISIBLE (1275 3200);
FORCEPROP 1 LAST PATH I90
J 0
(1275 3150);
DISPLAY 0.978723 (1275 3150);
PAINT WHITE (1275 3150);
DISPLAY INVISIBLE (1275 3150);
FORCEPROP 2 LAST SEC_TYPE 0402
J 0
(1275 3200);
DISPLAY 1.021277 (1275 3200);
PAINT ORANGE (1275 3200);
DISPLAY INVISIBLE (1275 3200);
FORCEPROP 2 LAST SEC 1
J 0
(1275 3200);
PAINT MONO (1275 3200);
DISPLAY INVISIBLE (1275 3200);
FORCEPROP 2 LAST CDS_LOCATION R8E7
J 0
(1275 3050);
DISPLAY 0.617021 (1275 3050);
PAINT AQUA (1275 3050);
DISPLAY INVISIBLE (1275 3050);
FORCEPROP 2 LAST CDS_LIB mstr_discrete
J 0
(1325 3000);
PAINT MONO (1325 3000);
DISPLAY INVISIBLE (1325 3000);
FORCEADD OFFPAGE..2
(2100 3000);
FORCEPROP 2 LASTPIN (2050 3000) SIG_NAME PWRGD_P12V_HSC_DLY
J 2
(1990 3010);
DISPLAY 0.617021 (1990 3010);
PAINT ORANGE (1990 3010);
FORCEPROP 2 LAST $XR2 248 
J 0
(2529 3000);
DISPLAY 0.638298 (2529 3000);
PAINT MONO (2529 3000);
FORCEPROP 2 LAST $XR1 241 
J 0
(2409 3000);
DISPLAY 0.638298 (2409 3000);
PAINT MONO (2409 3000);
FORCEPROP 2 LAST $XR0 181 
J 0
(2289 3000);
DISPLAY 0.638298 (2289 3000);
PAINT MONO (2289 3000);
FORCEPROP 2 LAST CDS_LIB mstr_standard
J 0
(2100 3000);
PAINT MONO (2100 3000);
DISPLAY INVISIBLE (2100 3000);
FORCEPROP 2 LAST PATH I91
J 0
(2275 3075);
DISPLAY 1.021277 (2275 3075);
PAINT ORANGE (2275 3075);
DISPLAY INVISIBLE (2275 3075);
FORCEPROP 1 LAST OFFPAGE TRUE
J 0
(2425 2875);
DISPLAY 0.872340 (2425 2875);
PAINT GREEN (2425 2875);
DISPLAY INVISIBLE (2425 2875);
FORCEPROP 1 LAST COMMENT_BODY TRUE
J 0
(2055 2905);
DISPLAY 0.872340 (2055 2905);
PAINT GREEN (2055 2905);
DISPLAY INVISIBLE (2055 2905);
FORCEADD CAP_A..1
(-300 2950);
FORCEPROP 1 LASTPIN (-300 3050) $PN 1
J 0
(-290 3030);
DISPLAY 0.617021 (-290 3030);
PAINT ORANGE (-290 3030);
FORCEPROP 1 LASTPIN (-300 2850) $PN 2
J 0
(-290 2830);
DISPLAY 0.617021 (-290 2830);
PAINT ORANGE (-290 2830);
FORCEPROP 1 LAST MATERIAL X7R
J 0
(-250 2850);
DISPLAY 0.617021 (-250 2850);
PAINT SKYBLUE (-250 2850);
FORCEPROP 1 LAST VOLTAGE 16V
J 0
(-250 2950);
DISPLAY 0.617021 (-250 2950);
PAINT SKYBLUE (-250 2950);
FORCEPROP 1 LAST PACK_TYPE 0402V
J 0
(-250 2750);
DISPLAY 0.617021 (-250 2750);
PAINT SKYBLUE (-250 2750);
FORCEPROP 1 LAST TOLERANCE 10%
J 0
(-250 2900);
DISPLAY 0.617021 (-250 2900);
PAINT SKYBLUE (-250 2900);
FORCEPROP 1 LAST VALUE 0.1UF
J 0
(-250 3000);
DISPLAY 0.617021 (-250 3000);
PAINT SKYBLUE (-250 3000);
FORCEPROP 1 LAST LOCATION C8E3
J 0
(-250 3050);
DISPLAY 0.617021 (-250 3050);
PAINT AQUA (-250 3050);
FORCEPROP 1 LAST PART_NUMBER A36096-030
J 0
(-250 2800);
DISPLAY 0.617021 (-250 2800);
PAINT BLUE (-250 2800);
FORCEPROP 2 LAST CDS_LIB dev_discrete
J 0
(-300 2950);
PAINT ORANGE (-300 2950);
DISPLAY INVISIBLE (-300 2950);
FORCEPROP 2 LAST CDS_LOCATION C8E3
J 0
(-250 3050);
DISPLAY 0.617021 (-250 3050);
PAINT AQUA (-250 3050);
DISPLAY INVISIBLE (-250 3050);
FORCEPROP 2 LAST ROOM V_SUPER
J 0
(-250 3100);
DISPLAY 1.021277 (-250 3100);
PAINT ORANGE (-250 3100);
DISPLAY INVISIBLE (-250 3100);
FORCEPROP 1 LAST PATH I94
J 0
(-250 3100);
DISPLAY 0.978723 (-250 3100);
PAINT WHITE (-250 3100);
DISPLAY INVISIBLE (-250 3100);
FORCEPROP 2 LAST SEC_TYPE 0402V
J 0
(-250 3150);
DISPLAY 1.021277 (-250 3150);
PAINT ORANGE (-250 3150);
DISPLAY INVISIBLE (-250 3150);
FORCEPROP 2 LAST SEC 1
J 0
(-250 3150);
DISPLAY 0.680851 (-250 3150);
PAINT MONO (-250 3150);
DISPLAY INVISIBLE (-250 3150);
FORCEADD GND..1
(-300 2750);
FORCEPROP 3 LASTPIN (-300 2800) SIG_NAME GND\g
J 0
(-290 2810);
DISPLAY 0.659574 (-290 2810);
PAINT MONO (-290 2810);
DISPLAY INVISIBLE (-290 2810);
FORCEPROP 1 LAST VOLTAGE 0.0V
J 0
(-345 2707);
DISPLAY 0.340426 (-345 2707);
PAINT SKYBLUE (-345 2707);
DISPLAY INVISIBLE (-345 2707);
FORCEPROP 2 LAST CDS_LIB mstr_symbols
J 0
(-300 2750);
PAINT MONO (-300 2750);
DISPLAY INVISIBLE (-300 2750);
FORCEPROP 1 LAST SIZE 1B
J 0
(-225 2700);
DISPLAY 0.872340 (-225 2700);
PAINT AQUA (-225 2700);
DISPLAY INVISIBLE (-225 2700);
FORCEPROP 1 LAST PATH I95
J 0
(-225 2750);
DISPLAY 0.872340 (-225 2750);
PAINT AQUA (-225 2750);
DISPLAY INVISIBLE (-225 2750);
FORCEPROP 1 LAST BODY_TYPE PLUMBING
J 0
(-345 2707);
DISPLAY 0.340426 (-345 2707);
PAINT GREEN (-345 2707);
DISPLAY INVISIBLE (-345 2707);
FORCEPROP 1 LAST HDL_POWER GND
J 0
(-300 2900);
DISPLAY 0.872340 (-300 2900);
PAINT GREEN (-300 2900);
DISPLAY INVISIBLE (-300 2900);
FORCEADD OFFPAGE..1
(-900 3150);
FORCEPROP 2 LASTPIN (-850 3150) SIG_NAME PWRGD_P12V_HSC
J 0
(-860 3160);
DISPLAY 0.617021 (-860 3160);
PAINT ORANGE (-860 3160);
FORCEPROP 2 LAST CDS_LIB mstr_standard
J 0
(-900 3150);
PAINT MONO (-900 3150);
DISPLAY INVISIBLE (-900 3150);
FORCEPROP 2 LAST PATH I96
J 0
(-850 3225);
DISPLAY 1.021277 (-850 3225);
PAINT ORANGE (-850 3225);
DISPLAY INVISIBLE (-850 3225);
FORCEPROP 1 LAST OFFPAGE TRUE
J 0
(-575 3025);
DISPLAY 0.872340 (-575 3025);
PAINT GREEN (-575 3025);
DISPLAY INVISIBLE (-575 3025);
FORCEPROP 1 LAST COMMENT_BODY TRUE
J 0
(-775 3050);
DISPLAY 0.872340 (-775 3050);
PAINT GREEN (-775 3050);
DISPLAY INVISIBLE (-775 3050);
FORCEPROP 2 LAST $XR0 199 
J 0
(-1326 3150);
DISPLAY 0.638298 (-1326 3150);
PAINT MONO (-1326 3150);
DISPLAY INVISIBLE (-1326 3150);
FORCEADD P3V3_RTC_STBY..1
(-2200 4875);
FORCEPROP 3 LASTPIN (-2200 4825) SIG_NAME P3V3_RTC_STBY\g
J 0
(-2190 4835);
DISPLAY 0.659574 (-2190 4835);
PAINT MONO (-2190 4835);
DISPLAY INVISIBLE (-2190 4835);
FORCEPROP 1 LAST VOLTAGE 3.3V
J 0
(-2245 4832);
DISPLAY 0.340426 (-2245 4832);
PAINT SKYBLUE (-2245 4832);
DISPLAY INVISIBLE (-2245 4832);
FORCEPROP 2 LAST ROOM SB_DECOUPLING
J 0
(-2200 4975);
DISPLAY 1.361702 (-2200 4975);
PAINT WHITE (-2200 4975);
DISPLAY INVISIBLE (-2200 4975);
FORCEPROP 1 LAST PATH I97
J 0
(-2150 4900);
DISPLAY 0.872340 (-2150 4900);
PAINT AQUA (-2150 4900);
DISPLAY INVISIBLE (-2150 4900);
FORCEPROP 2 LAST BOM_COST SB
J 0
(-2200 5025);
PAINT MONO (-2200 5025);
DISPLAY INVISIBLE (-2200 5025);
FORCEPROP 2 LAST CDS_LIB mstr_symbols
J 0
(-2200 4875);
PAINT ORANGE (-2200 4875);
DISPLAY INVISIBLE (-2200 4875);
FORCEPROP 1 LAST BODY_TYPE PLUMBING
J 0
(-2245 4832);
DISPLAY 0.340426 (-2245 4832);
PAINT GREEN (-2245 4832);
DISPLAY INVISIBLE (-2245 4832);
FORCEPROP 1 LAST HDL_POWER P3V3_RTC_STBY
J 1
(-2200 4925);
DISPLAY 0.872340 (-2200 4925);
PAINT GREEN (-2200 4925);
DISPLAY INVISIBLE (-2200 4925);
FORCEADD OFFPAGE..1
(-900 3650);
FORCEPROP 2 LASTPIN (-850 3650) SIG_NAME PWRGD_P3V3_STBY
J 0
(-735 3685);
DISPLAY 0.617021 (-735 3685);
PAINT ORANGE (-735 3685);
FORCEPROP 2 LAST $XR5 239 
J 0
(-1152 3614);
DISPLAY 0.638298 (-1152 3614);
PAINT MONO (-1152 3614);
FORCEPROP 2 LAST $XR4 237 
J 0
(-1632 3650);
DISPLAY 0.638298 (-1632 3650);
PAINT MONO (-1632 3650);
FORCEPROP 2 LAST $XR3 191 
J 0
(-1512 3650);
DISPLAY 0.638298 (-1512 3650);
PAINT MONO (-1512 3650);
FORCEPROP 2 LAST $XR2 189 
J 0
(-1392 3650);
DISPLAY 0.638298 (-1392 3650);
PAINT MONO (-1392 3650);
FORCEPROP 2 LAST $XR1 101 
J 0
(-1272 3650);
DISPLAY 0.638298 (-1272 3650);
PAINT MONO (-1272 3650);
FORCEPROP 2 LAST $XR0 240 
J 0
(-1152 3650);
DISPLAY 0.638298 (-1152 3650);
PAINT MONO (-1152 3650);
FORCEPROP 2 LAST PATH I98
J 0
(-850 3725);
DISPLAY 1.021277 (-850 3725);
PAINT ORANGE (-850 3725);
DISPLAY INVISIBLE (-850 3725);
FORCEPROP 2 LAST CDS_LIB mstr_standard
J 0
(-900 3650);
PAINT MONO (-900 3650);
DISPLAY INVISIBLE (-900 3650);
FORCEPROP 1 LAST OFFPAGE TRUE
J 0
(-575 3525);
DISPLAY 0.872340 (-575 3525);
PAINT GREEN (-575 3525);
DISPLAY INVISIBLE (-575 3525);
FORCEPROP 1 LAST COMMENT_BODY TRUE
J 0
(-775 3550);
DISPLAY 0.872340 (-775 3550);
PAINT GREEN (-775 3550);
DISPLAY INVISIBLE (-775 3550);
FORCEADD INTEL_CORP_BPAGE..1
(2650 500);
FORCEPROP 1 LAST CDS_CON_LAST_MODIFIED Fri Jun 16 17:49:12 2017
J 0
(1225 825);
PAINT ORANGE (1225 825);
DISPLAY INVISIBLE (1225 825);
FORCEPROP 1 LAST CUSTOM_TXT_CDS <CURRENT_DESIGN_SHEET> OF <TOTAL_DESIGN_SHEETS>
J 0
(2150 525);
PAINT ORANGE (2150 525);
FORCEPROP 1 LAST CUSTOM_TXT_CDS <CON_LAST_MODIFIED>
J 0
(-1350 600);
PAINT ORANGE (-1350 600);
FORCEPROP 2 LAST CUSTOM_TXT_CDS <XR_PAGE_TITLE>
J 0
(-5240 5750);
DISPLAY 0.638298 (-5240 5750);
PAINT PINK (-5240 5750);
DISPLAY INVISIBLE (-5240 5750);
FORCEPROP 1 LAST SCH_TITLE BATTERY CIRCUIT/VOLTAGE SUPERVISORS
J 0
(-5300 550);
DISPLAY 1.212766 (-5300 550);
PAINT ORANGE (-5300 550);
FORCEPROP 2 LAST PAGE_BORDER TRUE
J 0
(-5240 5750);
DISPLAY 0.851064 (-5240 5750);
PAINT PINK (-5240 5750);
DISPLAY INVISIBLE (-5240 5750);
FORCEPROP 2 LAST CDS_LIB mstr_symbols
J 0
(2650 500);
PAINT MONO (2650 500);
DISPLAY INVISIBLE (2650 500);
FORCEPROP 1 LAST COMMENT_BODY TRUE
J 0
(2662 512);
DISPLAY 0.468085 (2662 512);
PAINT GREEN (2662 512);
DISPLAY INVISIBLE (2662 512);
FORCEPROP 2 LAST CDS_XR_PAGE_TITLE CR-196 : @BASEBOARD_FAB2_LIB.BASEBOARD_FAB2(SCH_1):PAGE196
J 0
(-5240 5750);
DISPLAY 0.638298 (-5240 5750);
PAINT PINK (-5240 5750);
DISPLAY INVISIBLE (-5240 5750);
FORCEADD DESIGN_NOTE..1
(500 5425);
FORCEPROP 0 LAST L1 FOR ADM1085:
J 0
(300 5275);
DISPLAY 1.021277 (300 5275);
PAINT ORANGE (300 5275);
FORCEPROP 0 LAST L2 NOMINAL TRIP POINT IS 8.972V (8.204V~9.767V)
J 0
(300 5175);
DISPLAY 1.021277 (300 5175);
PAINT ORANGE (300 5175);
FORCEPROP 0 LAST L3 TARGET POWER ON DELAY IS 225MS
J 0
(300 5075);
DISPLAY 1.021277 (300 5075);
PAINT ORANGE (300 5075);
FORCEPROP 2 LAST CDS_LIB mstr_symbols
J 0
(500 5425);
PAINT ORANGE (500 5425);
DISPLAY INVISIBLE (500 5425);
FORCEPROP 1 LAST COMMENT_BODY TRUE
J 0
(525 5525);
DISPLAY 0.978723 (525 5525);
PAINT ORANGE (525 5525);
DISPLAY INVISIBLE (525 5525);
FORCEADD CAD_NOTE..1
(-2300 3950);
FORCEPROP 0 LAST L2 NEAR BATTERY HOLDER
J 0
(-2450 3775);
DISPLAY 0.617021 (-2450 3775);
PAINT WHITE (-2450 3775);
FORCEPROP 0 LAST L1 PLACE 1UF CLOSE TO DIODE
J 0
(-2450 3825);
DISPLAY 0.617021 (-2450 3825);
PAINT WHITE (-2450 3825);
FORCEPROP 2 LAST CDS_LIB mstr_symbols
J 0
(-2300 3950);
PAINT WHITE (-2300 3950);
DISPLAY INVISIBLE (-2300 3950);
FORCEPROP 1 LAST COMMENT_BODY TRUE
J 0
(-2275 4050);
DISPLAY 1.361702 (-2275 4050);
PAINT WHITE (-2275 4050);
DISPLAY INVISIBLE (-2275 4050);
FORCEADD DESIGN_NOTE..1
(-1950 3400);
FORCEPROP 0 LAST L1 ADM809S (2.93V TYPICAL) USED IN THESE 2 LOCATIONS.
J 0
(-2150 3250);
DISPLAY 1.021277 (-2150 3250);
PAINT ORANGE (-2150 3250);
FORCEPROP 2 LAST CDS_LIB mstr_symbols
J 0
(-1950 3400);
PAINT ORANGE (-1950 3400);
DISPLAY INVISIBLE (-1950 3400);
FORCEPROP 1 LAST COMMENT_BODY TRUE
J 0
(-1925 3500);
DISPLAY 0.978723 (-1925 3500);
PAINT ORANGE (-1925 3500);
DISPLAY INVISIBLE (-1925 3500);
FORCEADD DNS..2
(-20 4745);
PAINT RED (-20 4745);
FORCEPROP 2 LAST CDS_LIB mstr_misc
J 0
(-20 4745);
PAINT ORANGE (-20 4745);
DISPLAY INVISIBLE (-20 4745);
FORCEPROP 1 LAST COMMENT_BODY TRUE
R 1
J 0
(55 4520);
DISPLAY 0.872340 (55 4520);
PAINT GREEN (55 4520);
DISPLAY INVISIBLE (55 4520);
WIRE 16 -1 (-150 2150)(-150 2050);
WIRE 16 -1 (-200 2150)(-150 2150);
WIRE 16 -1 (-1000 1850)(-1000 1800);
WIRE 16 -1 (-1000 2700)(-1000 2400);
WIRE 16 -1 (-1000 2400)(-800 2400);
WIRE 16 -1 (-1000 2400)(-1000 2050);
WIRE 16 -1 (-1750 2000)(-1750 1950);
WIRE 16 -1 (-1750 3000)(-1750 2950);
WIRE 16 -1 (-1750 2300)(-1750 2225);
WIRE 16 -1 (-1750 1350)(-1750 1300);
WIRE 16 -1 (50 2800)(50 2750);
WIRE 16 -1 (750 1550)(750 1500);
WIRE 16 -1 (250 2250)(250 2100);
WIRE 16 -1 (750 2550)(750 2300);
WIRE 16 -1 (-2200 4400)(-2200 4300);
WIRE 16 -1 (-5050 4550)(-5050 4300);
WIRE 16 -1 (-5050 4550)(-4950 4550);
WIRE 16 -1 (-3250 4750)(-3250 4925);
WIRE 16 -1 (-2850 4750)(-3250 4750);
WIRE 16 -1 (-25 4850)(-25 4950);
WIRE 16 -1 (-525 4850)(-525 4950);
WIRE 16 -1 (1325 4750)(1325 4850);
WIRE 16 -1 (1125 4200)(1125 4150);
WIRE 16 -1 (1075 4200)(1125 4200);
WIRE 16 -1 (1225 3900)(1225 3950);
WIRE 16 -1 (275 4850)(275 4500);
WIRE 16 -1 (275 4500)(375 4500);
WIRE 16 -1 (275 4500)(275 4050);
WIRE 16 -1 (275 3800)(275 3850);
WIRE 16 -1 (-525 4150)(-525 4100);
WIRE 16 -1 (-300 1150)(-300 1100);
WIRE 16 -1 (-300 1450)(-300 1400);
WIRE 16 -1 (-300 1400)(0 1400);
WIRE 16 -1 (-300 1400)(-300 1350);
WIRE 16 -1 (-300 2850)(-300 2800);
WIRE 16 -1 (-2200 4825)(-2200 4650);
WIRE 16 -1 (-2200 4600)(-2200 4650);
WIRE 16 -1 (-2550 4650)(-2200 4650);
WIRE 16 -1 (-25 4650)(-25 4350);
WIRE 16 -1 (-25 4350)(375 4350);
WIRE 16 -1 (-25 3650)(-25 4350);
WIRE 16 -1 (-25 3650)(725 3650);
WIRE 16 -1 (-850 3650)(-25 3650);
WIRE 16 2175 (-5125 3550)(-1750 3550);
WIRE 16 2175 (-1750 5400)(-1750 3550);
WIRE 16 -1 (-525 4350)(-525 4450);
WIRE 16 -1 (-525 4450)(375 4450);
FORCEPROP 2 LAST SIG_NAME VSENSE_P12V_ADM1085
J 0
(-485 4460);
DISPLAY 0.617021 (-485 4460);
PAINT ORANGE (-485 4460);
FORCEPROP 2 LASTPROP $XRERR UNIQUE?
J 0
(-725 4460);
DISPLAY 0.638298 (-725 4460);
PAINT MONO (-725 4460);
DISPLAY INVISIBLE (-725 4460);
WIRE 16 -1 (-525 4650)(-525 4450);
WIRE 16 -1 (-4650 4600)(-4525 4600);
WIRE 16 -1 (-4650 4500)(-4525 4500);
WIRE 16 -1 (-4525 4500)(-4525 4550);
WIRE 16 -1 (-4525 4550)(-4525 4600);
WIRE 16 -1 (-4525 4550)(-3750 4550);
FORCEPROP 0 LAST VOLTAGE +3 V
J 0
(-4200 4675);
PAINT SKYBLUE (-4200 4675);
DISPLAY INVISIBLE (-4200 4675);
FORCEPROP 0 LAST CDS_PHYS_NET_NAME P3V_BAT_SOURCE
J 0
(-4200 4625);
DISPLAY 1.148936 (-4200 4625);
PAINT ORANGE (-4200 4625);
DISPLAY INVISIBLE (-4200 4625);
FORCEPROP 2 LAST SIG_NAME P3V_BAT_SOURCE
J 0
(-4410 4560);
DISPLAY 0.617021 (-4410 4560);
PAINT ORANGE (-4410 4560);
FORCEPROP 2 LASTPROP $XRERR UNIQUE?
J 0
(-4650 4560);
DISPLAY 0.638298 (-4650 4560);
PAINT MONO (-4650 4560);
DISPLAY INVISIBLE (-4650 4560);
WIRE 16 -1 (1800 1250)(1400 1250);
WIRE 16 -1 (1800 2000)(1450 2000);
WIRE 16 -1 (1225 4250)(1225 4150);
WIRE 16 -1 (1075 4250)(1225 4250);
FORCEPROP 2 LAST SIG_NAME A_ADM1085_CEXT
J 0
(1140 4260);
DISPLAY 0.617021 (1140 4260);
PAINT ORANGE (1140 4260);
FORCEPROP 2 LASTPROP $XRERR UNIQUE?
J 0
(900 4260);
DISPLAY 0.638298 (900 4260);
PAINT MONO (900 4260);
DISPLAY INVISIBLE (900 4260);
WIRE 16 -1 (1075 4350)(1325 4350);
WIRE 16 -1 (1325 4350)(1325 4550);
WIRE 16 -1 (1325 4350)(1525 4350);
WIRE 16 -1 (1975 4350)(1525 4350);
WIRE 16 -1 (1525 3650)(1525 4350);
WIRE 16 -1 (925 3650)(1525 3650);
WIRE 16 -1 (750 2000)(750 1950);
WIRE 16 -1 (750 2000)(1250 2000);
FORCEPROP 2 LAST SIG_NAME PWRGD_P5V_R
J 0
(990 2010);
DISPLAY 0.617021 (990 2010);
PAINT ORANGE (990 2010);
FORCEPROP 2 LASTPROP $XRERR UNIQUE?
J 0
(750 2010);
DISPLAY 0.638298 (750 2010);
PAINT MONO (750 2010);
DISPLAY INVISIBLE (750 2010);
WIRE 16 -1 (750 2100)(750 2000);
WIRE 16 -1 (1800 2400)(1450 2400);
WIRE 16 -1 (600 3000)(1225 3000);
FORCEPROP 2 LAST SIG_NAME PWRGD_P12V_HSC_DLY_R
J 2
(1165 3010);
DISPLAY 0.617021 (1165 3010);
PAINT ORANGE (1165 3010);
FORCEPROP 2 LASTPROP $XRERR UNIQUE?
J 0
(925 3010);
DISPLAY 0.638298 (925 3010);
PAINT MONO (925 3010);
DISPLAY INVISIBLE (925 3010);
WIRE 16 -1 (400 1250)(1200 1250);
FORCEPROP 2 LAST SIG_NAME PWRGD_P3V3_R1
J 0
(515 1260);
DISPLAY 0.617021 (515 1260);
PAINT ORANGE (515 1260);
FORCEPROP 2 LASTPROP $XRERR UNIQUE?
J 0
(275 1260);
DISPLAY 0.638298 (275 1260);
PAINT MONO (275 1260);
DISPLAY INVISIBLE (275 1260);
WIRE 16 -1 (-2850 4300)(-3250 4300);
FORCEPROP 0 LAST VOLTAGE +3 V
J 0
(-3175 4375);
PAINT SKYBLUE (-3175 4375);
DISPLAY INVISIBLE (-3175 4375);
FORCEPROP 2 LAST SIG_NAME A_P3V_BAT_R
J 0
(-3185 4310);
DISPLAY 0.617021 (-3185 4310);
PAINT ORANGE (-3185 4310);
WIRE 16 -1 (-3250 4550)(-3250 4300);
WIRE 16 -1 (-3250 4550)(-2850 4550);
WIRE 16 -1 (-3550 4550)(-3250 4550);
FORCEPROP 0 LAST CDS_PHYS_NET_NAME P3V_BAT_R
J 0
(-3350 4625);
DISPLAY 1.148936 (-3350 4625);
PAINT ORANGE (-3350 4625);
DISPLAY INVISIBLE (-3350 4625);
WIRE 16 -1 (1150 3400)(1525 3400);
WIRE 16 -1 (1525 3000)(1425 3000);
WIRE 16 -1 (1525 3400)(1525 3000);
WIRE 16 -1 (2050 3000)(1525 3000);
WIRE 16 -1 (-200 2400)(50 2400);
WIRE 16 -1 (50 2550)(50 2400);
WIRE 16 -1 (1250 2400)(50 2400);
FORCEPROP 2 LAST SIG_NAME PWRGD_P12V_MAIN_R
J 0
(815 2410);
DISPLAY 0.617021 (815 2410);
PAINT ORANGE (815 2410);
FORCEPROP 2 LASTPROP $XRERR UNIQUE?
J 0
(575 2410);
DISPLAY 0.638298 (575 2410);
PAINT MONO (575 2410);
DISPLAY INVISIBLE (575 2410);
WIRE 16 -1 (250 1900)(250 1650);
WIRE 16 -1 (250 1650)(550 1650);
WIRE 16 -1 (0 1650)(250 1650);
WIRE 16 -1 (-200 2300)(0 2300);
WIRE 16 -1 (0 2300)(0 1650);
FORCEPROP 2 LAST SIG_NAME PWRGD_P5V_N
J 0
(290 1660);
DISPLAY 0.617021 (290 1660);
PAINT ORANGE (290 1660);
FORCEPROP 2 LASTPROP $XRERR UNIQUE?
J 0
(50 1660);
DISPLAY 0.638298 (50 1660);
PAINT MONO (50 1660);
DISPLAY INVISIBLE (50 1660);
WIRE 16 -1 (-1150 2150)(-800 2150);
WIRE 16 -1 (-1150 1650)(-1150 2150);
WIRE 16 -1 (-1750 1650)(-1750 1550);
WIRE 16 -1 (-1750 1750)(-1750 1650);
WIRE 16 -1 (-1750 1650)(-1150 1650);
FORCEPROP 2 LAST SIG_NAME A_PG_P5V
J 0
(-1460 1660);
DISPLAY 0.617021 (-1460 1660);
PAINT ORANGE (-1460 1660);
FORCEPROP 2 LASTPROP $XRERR UNIQUE?
J 0
(-1700 1660);
DISPLAY 0.638298 (-1700 1660);
PAINT MONO (-1700 1660);
DISPLAY INVISIBLE (-1700 1660);
WIRE 16 -1 (-1150 2250)(-800 2250);
WIRE 16 -1 (-1150 2600)(-1150 2250);
WIRE 16 -1 (-1750 2600)(-1750 2500);
WIRE 16 -1 (-1750 2600)(-1150 2600);
FORCEPROP 2 LAST SIG_NAME A_PG_P12V_MAIN
J 0
(-1460 2610);
DISPLAY 0.617021 (-1460 2610);
PAINT ORANGE (-1460 2610);
FORCEPROP 2 LASTPROP $XRERR UNIQUE?
J 0
(-1700 2610);
DISPLAY 0.638298 (-1700 2610);
PAINT MONO (-1700 2610);
DISPLAY INVISIBLE (-1700 2610);
WIRE 16 -1 (-1750 2750)(-1750 2600);
WIRE 16 -1 (950 3400)(-50 3400);
WIRE 16 -1 (-50 3400)(-50 3150);
WIRE 16 -1 (-50 3150)(200 3150);
WIRE 16 -1 (-300 3150)(-300 3050);
WIRE 16 -1 (-850 3150)(-300 3150);
WIRE 16 -1 (-300 3150)(-50 3150);
WIRE 3 682 (-1800 2150)(-1800 2575);
WIRE 3 682 (-1500 2150)(-1800 2150);
WIRE 3 682 (-1800 2575)(-1500 2575);
WIRE 3 682 (-1500 2575)(-1500 2150);
WIRE 3 682 (-1850 2650)(-1300 2650);
WIRE 3 682 (-1850 3150)(-1850 2650);
WIRE 3 682 (-1300 2650)(-1300 3150);
WIRE 3 682 (-1300 3150)(-1850 3150);
DOT 1 (-1750 2600);
DOT 1 (-1000 2400);
DOT 1 (-4525 4550);
DOT 1 (-1750 1650);
DOT 1 (-300 1400);
DOT 1 (-300 3150);
DOT 1 (-50 3150);
DOT 1 (-25 3650);
DOT 1 (-3250 4550);
DOT 1 (-2200 4650);
DOT 1 (-25 4350);
DOT 1 (250 1650);
DOT 1 (750 2000);
DOT 1 (50 2400);
DOT 1 (275 4500);
DOT 1 (1525 4350);
DOT 1 (1325 4350);
DOT 1 (1525 3000);
DOT 1 (-525 4450);
FORCENOTE
P12V < 10.47 PWRGD_P12V_MAIN DEASSERT
(-3850 2100) 0;
DISPLAY LEFT (-3850 2100);
DISPLAY 1.021277 (-3850 2100);
PAINT PURPLE (-3850 2100);
FORCENOTE
P12V >= 10.62 PWRGD_P12V_MAIN ASSERT
(-3850 2150) 0;
DISPLAY LEFT (-3850 2150);
DISPLAY 1.021277 (-3850 2150);
PAINT PURPLE (-3850 2150);
FORCENOTE
TP FAB3-DVT CHANGE R8D40 FROM 3.74K TO 20K 20161208
(-2900 2250) 0;
DISPLAY LEFT (-2900 2250);
DISPLAY 0.638298 (-2900 2250);
PAINT RED (-2900 2250);
FORCENOTE
TP FAB3-DVT CHANGE R3D38 FROM 100K TO 511K 20161208
(-2600 3175) 0;
DISPLAY LEFT (-2600 3175);
DISPLAY 0.638298 (-2600 3175);
PAINT RED (-2600 3175);
FORCENOTE
P5V >= 4.539V (4.687V~4.372V): PWRGD_5V ASSERT
(-3800 1150) 0;
DISPLAY LEFT (-3800 1150);
DISPLAY 1.021277 (-3800 1150);
PAINT PURPLE (-3800 1150);
FORCENOTE
COIN TYPE BATTERY
(-4550 4075) 0;
DISPLAY LEFT (-4550 4075);
DISPLAY 0.617021 (-4550 4075);
PAINT PURPLE (-4550 4075);
FORCENOTE
BATTERY
(-3425 5250) 0;
DISPLAY LEFT (-3425 5250);
DISPLAY 0.617021 (-3425 5250);
PAINT PURPLE (-3425 5250);
FORCENOTE
ROOM = V_SUPER
(-450 900) 0;
DISPLAY LEFT (-450 900);
DISPLAY 1.021277 (-450 900);
PAINT PURPLE (-450 900);
QUIT
